G04 ================== begin FILE IDENTIFICATION RECORD ==================*
G04 Layout Name:  D:/<user>/Wistron_project/16316-1/gbr-0621/16316-1.brd*
G04 Film Name:    DP_REF_L3*
G04 File Format:  Gerber RS274X*
G04 File Origin:  Cadence Allegro 16.5-S056*
G04 Origin Date:  Wed Jun 21 09:32:27 2017*
G04 *
G04 Layer:  BOARD GEOMETRY/DP_REF_L3_TBL*
G04 Layer:  BOARD GEOMETRY/DP_REF_L3_L3*
G04 Layer:  BOARD GEOMETRY/PANEL_OUTLINE*
G04 *
G04 Offset:    (0.00 0.00)*
G04 Mirror:    No*
G04 Mode:      Positive*
G04 Rotation:  0*
G04 FullContactRelief:  No*
G04 UndefLineWidth:     6.00*
G04 ================== end FILE IDENTIFICATION RECORD ====================*
%FSLAX35Y35*MOIN*%
%IR0*IPPOS*OFA0.00000B0.00000*MIA0B0*SFA1.00000B1.00000*%
%ADD10C,.02*%
%ADD11C,.004*%
%ADD12C,.006*%
G75*
%LPD*%
G75*
G54D10*
G01X877071Y397916D02*
X1682071D01*
G01X877071Y363266D02*
X1682071D01*
G01X877071Y536516D02*
Y363266D01*
G01Y467216D02*
X1682071D01*
G01X877071Y432566D02*
X1682071D01*
G01X877071Y536516D02*
X1682071D01*
G01X877071Y501866D02*
X1682071D01*
G01X1052071Y536516D02*
Y363266D01*
G01X1367071Y536516D02*
Y363266D01*
G01X1472071Y536516D02*
Y363266D01*
G01X1682071Y536516D02*
Y363266D01*
G54D11*
G01X510483Y234853D02*
X511938D01*
G01X510483Y233653D02*
X512436D01*
G01X510483Y234853D02*
X511938D01*
G01X510483Y233653D02*
X512436D01*
G01X510483Y234853D02*
X511938D01*
G01X509050Y223036D02*
X529338D01*
G01X509050Y221836D02*
X529836D01*
G01X509050D02*
X529836D01*
G01X509050Y223036D02*
X529338D01*
G01X510450Y194290D02*
Y199711D01*
G01X509250Y193792D02*
Y199711D01*
G01X514358Y190382D02*
X510450Y194290D01*
G01X513158Y189884D02*
X509250Y193792D01*
G01X510902Y183281D02*
X512308D01*
G01X509250Y193792D02*
Y199711D01*
G01X510450Y194290D02*
Y199711D01*
G01X513158Y189884D02*
X509250Y193792D01*
G01X514358Y190382D02*
X510450Y194290D01*
G01X510902Y183281D02*
X512308D01*
G01X503998Y182139D02*
X500829D01*
G01X503998Y183339D02*
X500777D01*
G01X506515Y184656D02*
G02X503998Y182139I-2517J0D01*
G01X505315Y184656D02*
G02X503998Y183339I-1317J0D01*
G01X506515Y187764D02*
Y184656D01*
G01X505315Y199175D02*
Y184656D01*
G01X506515Y199175D02*
Y190464D01*
G01X505315Y199175D02*
Y184656D01*
G01X503998Y183339D02*
X500777D01*
G01X503998Y182139D02*
X500829D01*
G01X505315Y184656D02*
G02X503998Y183339I-1317J0D01*
G01X506515Y184656D02*
G02X503998Y182139I-2517J0D01*
G01X505315Y199175D02*
Y184656D01*
G01X506515Y187764D02*
Y184656D01*
G01Y199175D02*
Y190464D01*
G01X502568Y195592D02*
Y199667D01*
G01X501368Y196090D02*
Y199667D01*
G01X501719Y194743D02*
X502568Y195592D01*
G01X493724Y188446D02*
X501368Y196090D01*
G01X499810Y192834D02*
X500871D01*
G01X493724Y188446D02*
X501368Y196090D01*
G01X494924Y187948D02*
X499810Y192834D01*
G01X493724Y188446D02*
X501368Y196090D01*
G01X494924Y184541D02*
Y187948D01*
G01X493724Y184541D02*
Y188446D01*
G01X492580Y182197D02*
G03X494924Y184541I0J2344D01*
G01X492580Y183397D02*
G03X493724Y184541I0J1144D01*
G01X491404Y182197D02*
X492580D01*
G01X491352Y183397D02*
X492580D01*
G01X501368Y196090D02*
Y199667D01*
G01X502568Y195592D02*
Y199667D01*
G01X493724Y188446D02*
X501368Y196090D01*
G01X501719Y194743D02*
X502568Y195592D01*
G01X499810Y192834D02*
X500871D01*
G01X494924Y187948D02*
X499810Y192834D01*
G01X493724Y184541D02*
Y188446D01*
G01X494924Y184541D02*
Y187948D01*
G01X492580Y183397D02*
G03X493724Y184541I0J1144D01*
G01X492580Y182197D02*
G03X494924Y184541I0J2344D01*
G01X491352Y183397D02*
X492580D01*
G01X491404Y182197D02*
X492580D01*
G01X519838Y236174D02*
X535810Y252146D01*
G01X519340Y237374D02*
X532554Y250588D01*
G01X519838Y236174D02*
X535810Y252146D01*
G01X514459Y237374D02*
X519340D01*
G01X514957Y236174D02*
X519838D01*
G01X511938Y234853D02*
X514459Y237374D01*
G01X512436Y233653D02*
X514957Y236174D01*
G01X512436Y233653D02*
X514957Y236174D01*
G01X519838D02*
X535810Y252146D01*
G01X519340Y237374D02*
X532554Y250588D01*
G01X514957Y236174D02*
X519838D01*
G01X514459Y237374D02*
X519340D01*
G01X512436Y233653D02*
X514957Y236174D01*
G01X511938Y234853D02*
X514459Y237374D01*
G01X522401Y231299D02*
X535661Y244559D01*
G01X521903Y232499D02*
X532405Y243001D01*
G01X522401Y231299D02*
X535661Y244559D01*
G01X518472Y232499D02*
X521903D01*
G01X518472Y231299D02*
X522401D01*
G01D02*
X535661Y244559D01*
G01X521903Y232499D02*
X532405Y243001D01*
G01X518472Y231299D02*
X522401D01*
G01X518472Y232499D02*
X521903D01*
G01X548163Y236988D02*
G03X550215Y239040I0J2052D01*
G01X536404Y236988D02*
X548163D01*
G01X535057Y237339D02*
X535906Y238188D01*
G01X527519Y228103D02*
X536404Y236988D01*
G01X533997Y237339D02*
X535057D01*
G01X527519Y228103D02*
X536404Y236988D01*
G01X527021Y229303D02*
X533148Y235430D01*
G01X527519Y228103D02*
X536404Y236988D01*
G01X518488Y229303D02*
X527021D01*
G01X518488Y228103D02*
X527519D01*
G01X548163Y236988D02*
G03X550215Y239040I0J2052D01*
G01X536404Y236988D02*
X548163D01*
G01X527519Y228103D02*
X536404Y236988D01*
G01X535057Y237339D02*
X535906Y238188D01*
G01X533997Y237339D02*
X535057D01*
G01X527021Y229303D02*
X533148Y235430D01*
G01X518488Y228103D02*
X527519D01*
G01X518488Y229303D02*
X527021D01*
G01X550650Y230302D02*
Y231175D01*
G01X551850Y230302D02*
Y231239D01*
G01X549798Y229450D02*
G03X550650Y230302I0J852D01*
G01X549798Y228250D02*
G03X551850Y230302I0J2052D01*
G01X540436Y229450D02*
X549798D01*
G01X536250Y228250D02*
X549798D01*
G01X535752Y229450D02*
X537736D01*
G01X536250Y228250D02*
X549798D01*
G01X529338Y223036D02*
X535752Y229450D01*
G01X529836Y221836D02*
X536250Y228250D01*
G01X551850Y230302D02*
Y231239D01*
G01X550650Y230302D02*
Y231175D01*
G01X549798Y228250D02*
G03X551850Y230302I0J2052D01*
G01X549798Y229450D02*
G03X550650Y230302I0J852D01*
G01X536250Y228250D02*
X549798D01*
G01X540436Y229450D02*
X549798D01*
G01X535752D02*
X537736D01*
G01X529836Y221836D02*
X536250Y228250D01*
G01X529338Y223036D02*
X535752Y229450D01*
G01X514800Y201371D02*
Y211838D01*
G01X513600Y200873D02*
Y211838D01*
G01X522446Y193725D02*
X514800Y201371D01*
G01X524004Y190469D02*
X513600Y200873D01*
G01X525204Y190967D02*
X524355Y191816D01*
G01X524004Y190469D02*
X513600Y200873D01*
G01X525204Y184055D02*
Y190967D01*
G01X524004Y184055D02*
Y190469D01*
G01X523172Y182023D02*
G03X525204Y184055I0J2032D01*
G01X523172Y183223D02*
G03X524004Y184055I0J832D01*
G01X521079Y182023D02*
X523172D01*
G01X521027Y183223D02*
X523172D01*
G01X513600Y200873D02*
Y211838D01*
G01X514800Y201371D02*
Y211838D01*
G01X524004Y190469D02*
X513600Y200873D01*
G01X522446Y193725D02*
X514800Y201371D01*
G01X525204Y190967D02*
X524355Y191816D01*
G01X524004Y184055D02*
Y190469D01*
G01X525204Y184055D02*
Y190967D01*
G01X523172Y183223D02*
G03X524004Y184055I0J832D01*
G01X523172Y182023D02*
G03X525204Y184055I0J2032D01*
G01X521027Y183223D02*
X523172D01*
G01X521079Y182023D02*
X523172D01*
G01X514358Y188960D02*
Y190382D01*
G01X513158Y184131D02*
Y189884D01*
G01X514358Y184131D02*
Y186260D01*
G01X513158Y184131D02*
Y189884D01*
G01X512308Y182081D02*
G03X514358Y184131I0J2050D01*
G01X512308Y183281D02*
G03X513158Y184131I0J850D01*
G01X510954Y182081D02*
X512308D01*
G01X513158Y184131D02*
Y189884D01*
G01X514358Y188960D02*
Y190382D01*
G01Y184131D02*
Y186260D01*
G01X512308Y183281D02*
G03X513158Y184131I0J850D01*
G01X512308Y182081D02*
G03X514358Y184131I0J2050D01*
G01X510954Y182081D02*
X512308D01*
G01X547867Y254198D02*
Y255071D01*
G01X549067Y254198D02*
Y255135D01*
G01X547015Y253346D02*
G03X547867Y254198I0J852D01*
G01X547015Y252146D02*
G03X549067Y254198I0J2052D01*
G01X535312Y253346D02*
X547015D01*
G01X535810Y252146D02*
X547015D01*
G01X534463Y252497D02*
X535312Y253346D01*
G01X549067Y254198D02*
Y255135D01*
G01X547867Y254198D02*
Y255071D01*
G01X547015Y252146D02*
G03X549067Y254198I0J2052D01*
G01X547015Y253346D02*
G03X547867Y254198I0J852D01*
G01X535810Y252146D02*
X547015D01*
G01X535312Y253346D02*
X547015D01*
G01X534463Y252497D02*
X535312Y253346D01*
G01X548125Y246611D02*
Y247484D01*
G01X549325Y246611D02*
Y247548D01*
G01X547273Y245759D02*
G03X548125Y246611I0J852D01*
G01X547273Y244559D02*
G03X549325Y246611I0J2052D01*
G01X535163Y245759D02*
X547273D01*
G01X535661Y244559D02*
X547273D01*
G01X534314Y244910D02*
X535163Y245759D01*
G01X549325Y246611D02*
Y247548D01*
G01X548125Y246611D02*
Y247484D01*
G01X547273Y244559D02*
G03X549325Y246611I0J2052D01*
G01X547273Y245759D02*
G03X548125Y246611I0J852D01*
G01X535661Y244559D02*
X547273D01*
G01X535163Y245759D02*
X547273D01*
G01X534314Y244910D02*
X535163Y245759D01*
G01X549015Y239040D02*
Y239913D01*
G01X550215Y239040D02*
Y239977D01*
G01X548163Y238188D02*
G03X549015Y239040I0J852D01*
G01X535906Y238188D02*
X548163D01*
G01X550215Y239040D02*
Y239977D01*
G01X549015Y239040D02*
Y239913D01*
G01X548163Y238188D02*
G03X549015Y239040I0J852D01*
G01X535906Y238188D02*
X548163D01*
G01X620552Y164110D02*
X605429Y187409D01*
G01X619684Y163242D02*
X604301Y186942D01*
G01X641802Y150313D02*
X620552Y164110D01*
G01X641335Y149185D02*
X619684Y163242D01*
G01D02*
X604301Y186942D01*
G01X620552Y164110D02*
X605429Y187409D01*
G01X641335Y149185D02*
X619684Y163242D01*
G01X641802Y150313D02*
X620552Y164110D01*
G01X638166Y145322D02*
X615926Y159764D01*
G01X634356Y149228D02*
X635362Y148574D01*
G01X638166Y145322D02*
X615926Y159764D01*
G01X616794Y160632D02*
X632091Y150698D01*
G01X638166Y145322D02*
X615926Y159764D01*
G01X616100Y161701D02*
X616794Y160632D01*
G01X615926Y159764D02*
X596733Y189315D01*
G01X613976Y164971D02*
X614629Y163965D01*
G01X615926Y159764D02*
X596733Y189315D01*
G01X611851Y168242D02*
X612505Y167236D01*
G01X615926Y159764D02*
X596733Y189315D01*
G01X597861Y189782D02*
X610381Y170506D01*
G01X615926Y159764D02*
X596733Y189315D01*
G01X615926Y159764D02*
X596733Y189315D01*
G01X616100Y161701D02*
X616794Y160632D01*
G01X613976Y164971D02*
X614629Y163965D01*
G01X611851Y168242D02*
X612505Y167236D01*
G01X597861Y189782D02*
X610381Y170506D01*
G01X638166Y145322D02*
X615926Y159764D01*
G01X634356Y149228D02*
X635362Y148574D01*
G01X616794Y160632D02*
X632091Y150698D01*
G01X616390Y154209D02*
X636897Y140883D01*
G01X615522Y153341D02*
X633075Y141935D01*
G01X597286Y183634D02*
X616390Y154209D01*
G01X611881Y158948D02*
X615522Y153341D01*
G01X605831Y168267D02*
X611881Y158948D01*
G01X596418Y182766D02*
X605831Y168267D01*
G01X616390Y154209D02*
X636897Y140883D01*
G01X615522Y153341D02*
X633075Y141935D01*
G01X616390Y154209D02*
X636897Y140883D01*
G01X611881Y158948D02*
X615522Y153341D01*
G01X597286Y183634D02*
X616390Y154209D01*
G01X605831Y168267D02*
X611881Y158948D01*
G01X597286Y183634D02*
X616390Y154209D01*
G01X596418Y182766D02*
X605831Y168267D01*
G01X597286Y183634D02*
X616390Y154209D01*
G01X596174Y175364D02*
X593159Y176452D01*
G01X597183Y174710D02*
X596174Y175364D01*
G01X615041Y149406D02*
X598051Y175578D01*
G01X614173Y148538D02*
X597183Y174710D01*
G01X616047Y148752D02*
X615041Y149406D01*
G01X614890Y148072D02*
X614173Y148538D01*
G01X633558Y135950D02*
X614890Y148072D01*
G01X619318Y146628D02*
X618312Y147282D01*
G01X633558Y135950D02*
X614890Y148072D01*
G01X622589Y144504D02*
X621583Y145158D01*
G01X633558Y135950D02*
X614890Y148072D01*
G01X625860Y142380D02*
X624854Y143034D01*
G01X633558Y135950D02*
X614890Y148072D01*
G01X634025Y137078D02*
X628125Y140910D01*
G01X633558Y135950D02*
X614890Y148072D01*
G01X637535Y136333D02*
X634025Y137078D01*
G01X641958Y134167D02*
X633558Y135950D01*
G01X641958Y134167D02*
X633558Y135950D01*
G01X596174Y175364D02*
X593159Y176452D01*
G01X597183Y174710D02*
X596174Y175364D01*
G01X614173Y148538D02*
X597183Y174710D01*
G01X615041Y149406D02*
X598051Y175578D01*
G01X614890Y148072D02*
X614173Y148538D01*
G01X616047Y148752D02*
X615041Y149406D01*
G01X633558Y135950D02*
X614890Y148072D01*
G01X616047Y148752D02*
X615041Y149406D01*
G01X619318Y146628D02*
X618312Y147282D01*
G01X622589Y144504D02*
X621583Y145158D01*
G01X625860Y142380D02*
X624854Y143034D01*
G01X634025Y137078D02*
X628125Y140910D01*
G01X641958Y134167D02*
X633558Y135950D01*
G01X637535Y136333D02*
X634025Y137078D01*
G01X636026Y130605D02*
X634809Y130863D01*
G01X611513Y147423D02*
X635276Y131991D01*
G01X634809Y130863D02*
X610645Y146555D01*
G01X606325Y155412D02*
X611513Y147423D01*
G01X610645Y146555D02*
X605457Y154544D01*
G01X597100Y161400D02*
X606325Y155412D01*
G01X598613Y158987D02*
X596598Y160295D01*
G01X605457Y154544D02*
X600878Y157516D01*
G01X592545Y162693D02*
X597100Y161400D01*
G01X596598Y160295D02*
X592503Y161457D01*
G01X586003Y161305D02*
X592545Y162693D01*
G01X592503Y161457D02*
X586253Y160131D01*
G01X585953Y161294D02*
G02X586003Y161305I396J-1681D01*
G01X586253Y160131D02*
G03X585922Y159903I110J-515D01*
G01X586253Y160131D02*
G03X585922Y159903I110J-515D01*
G01X585953Y161294D02*
G02X586003Y161305I396J-1681D01*
G01X592503Y161457D02*
X586253Y160131D01*
G01X586003Y161305D02*
X592545Y162693D01*
G01X596598Y160295D02*
X592503Y161457D01*
G01X592545Y162693D02*
X597100Y161400D01*
G01X598613Y158987D02*
X596598Y160295D01*
G01X597100Y161400D02*
X606325Y155412D01*
G01X605457Y154544D02*
X600878Y157516D01*
G01X597100Y161400D02*
X606325Y155412D01*
G01X610645Y146555D02*
X605457Y154544D01*
G01X606325Y155412D02*
X611513Y147423D01*
G01X634809Y130863D02*
X610645Y146555D01*
G01X611513Y147423D02*
X635276Y131991D01*
G01X636026Y130605D02*
X634809Y130863D01*
G01X595324Y152477D02*
G03X595274Y152466I346J-1692D01*
G01X595574Y151303D02*
G03X595243Y151075I110J-515D01*
G01X598938Y153245D02*
X595324Y152477D01*
G01X598921Y152014D02*
X595574Y151303D01*
G01X602452Y152396D02*
X598938Y153245D01*
G01X601970Y151277D02*
X598921Y152014D01*
G01X604540Y151041D02*
X602452Y152396D01*
G01X603672Y150173D02*
X601970Y151277D01*
G01X609296Y143717D02*
X604540Y151041D01*
G01X608428Y142849D02*
X603672Y150173D01*
G01X610302Y143063D02*
X609296Y143717D01*
G01X609145Y142383D02*
X608428Y142849D01*
G01X632999Y126894D02*
X609145Y142383D01*
G01X613573Y140939D02*
X612567Y141593D01*
G01X632999Y126894D02*
X609145Y142383D01*
G01X616844Y138815D02*
X615838Y139469D01*
G01X632999Y126894D02*
X609145Y142383D01*
G01X623542Y134466D02*
X619109Y137345D01*
G01X632999Y126894D02*
X609145Y142383D01*
G01X626813Y132342D02*
X625807Y132996D01*
G01X632999Y126894D02*
X609145Y142383D01*
G01X630084Y130218D02*
X629078Y130872D01*
G01X632999Y126894D02*
X609145Y142383D01*
G01X633355Y128094D02*
X632349Y128748D01*
G01X632999Y126894D02*
X609145Y142383D01*
G01X644406Y128094D02*
X633355D01*
G01X643908Y126894D02*
X632999D01*
G01X595574Y151303D02*
G03X595243Y151075I110J-515D01*
G01X595324Y152477D02*
G03X595274Y152466I346J-1692D01*
G01X598921Y152014D02*
X595574Y151303D01*
G01X598938Y153245D02*
X595324Y152477D01*
G01X601970Y151277D02*
X598921Y152014D01*
G01X602452Y152396D02*
X598938Y153245D01*
G01X603672Y150173D02*
X601970Y151277D01*
G01X604540Y151041D02*
X602452Y152396D01*
G01X608428Y142849D02*
X603672Y150173D01*
G01X609296Y143717D02*
X604540Y151041D01*
G01X609145Y142383D02*
X608428Y142849D01*
G01X610302Y143063D02*
X609296Y143717D01*
G01X632999Y126894D02*
X609145Y142383D01*
G01X610302Y143063D02*
X609296Y143717D01*
G01X613573Y140939D02*
X612567Y141593D01*
G01X616844Y138815D02*
X615838Y139469D01*
G01X623542Y134466D02*
X619109Y137345D01*
G01X626813Y132342D02*
X625807Y132996D01*
G01X630084Y130218D02*
X629078Y130872D01*
G01X633355Y128094D02*
X632349Y128748D01*
G01X643908Y126894D02*
X632999D01*
G01X644406Y128094D02*
X633355D01*
G01X592293Y141906D02*
X587982Y141116D01*
G01X592276Y140682D02*
X588225Y139940D01*
G01X592431Y141876D02*
X592429D01*
G01X592276Y140682D02*
X588225Y139940D01*
G01X603205Y139587D02*
X592431Y141877D01*
G01X602738Y138459D02*
X592276Y140682D01*
G01X620041Y128653D02*
X603205Y139587D01*
G01X613776Y131290D02*
X602738Y138459D01*
G01X625652Y125007D02*
X620041Y128653D01*
G01X625185Y123879D02*
X613776Y131290D01*
G01X644974Y120900D02*
X625652Y125007D01*
G01X644847Y119700D02*
X625185Y123879D01*
G01X592276Y140682D02*
X588225Y139940D01*
G01X592293Y141906D02*
X587982Y141116D01*
G01X592431Y141876D02*
X592429D01*
G01X602738Y138459D02*
X592276Y140682D01*
G01X603205Y139587D02*
X592431Y141877D01*
G01X613776Y131290D02*
X602738Y138459D01*
G01X620041Y128653D02*
X603205Y139587D01*
G01X625185Y123879D02*
X613776Y131290D01*
G01X625652Y125007D02*
X620041Y128653D01*
G01X644847Y119700D02*
X625185Y123879D01*
G01X644974Y120900D02*
X625652Y125007D01*
G01X642939Y114735D02*
X624167Y118725D01*
G01X633936Y117876D02*
X635110Y117626D01*
G01X642939Y114735D02*
X624167Y118725D01*
G01X624634Y119853D02*
X631295Y118437D01*
G01X642939Y114735D02*
X624167Y118725D01*
G01X613260Y127240D02*
X624634Y119853D01*
G01X624167Y118725D02*
X612793Y126112D01*
G01X605305Y128931D02*
X613260Y127240D01*
G01X612793Y126112D02*
X587878Y131408D01*
G01X601490Y129742D02*
X602664Y129492D01*
G01X612793Y126112D02*
X587878Y131408D01*
G01X597675Y130553D02*
X598849Y130303D01*
G01X612793Y126112D02*
X587878Y131408D01*
G01Y132635D02*
X595034Y131114D01*
G01X612793Y126112D02*
X587878Y131408D01*
G01X586272Y132297D02*
X587878Y132635D01*
G01Y131408D02*
X586521Y131123D01*
G01X578838Y130714D02*
X586272Y132297D01*
G01X586521Y131123D02*
X579088Y129540D01*
G01X576740Y130268D02*
X578838Y130714D01*
G01X579088Y129540D02*
X577040Y129105D01*
G01X579088Y129540D02*
X577040Y129105D01*
G01X576740Y130268D02*
X578838Y130714D01*
G01X586521Y131123D02*
X579088Y129540D01*
G01X578838Y130714D02*
X586272Y132297D01*
G01X587878Y131408D02*
X586521Y131123D01*
G01X586272Y132297D02*
X587878Y132635D01*
G01X612793Y126112D02*
X587878Y131408D01*
G01X605305Y128931D02*
X613260Y127240D01*
G01X601490Y129742D02*
X602664Y129492D01*
G01X597675Y130553D02*
X598849Y130303D01*
G01X587878Y132635D02*
X595034Y131114D01*
G01X624167Y118725D02*
X612793Y126112D01*
G01X613260Y127240D02*
X624634Y119853D01*
G01X642939Y114735D02*
X624167Y118725D01*
G01X633936Y117876D02*
X635110Y117626D01*
G01X624634Y119853D02*
X631295Y118437D01*
G01X591364Y217494D02*
X589007Y216994D01*
G01X591213Y216235D02*
X589289Y215826D01*
G01X596772Y214897D02*
X591364Y217494D01*
G01X595949Y213961D02*
X591213Y216235D01*
G01X600949Y208469D02*
X596772Y214897D01*
G01X599821Y208001D02*
X595949Y213961D01*
G01X605429Y187409D02*
X600949Y208469D01*
G01X600071Y206827D02*
X599821Y208001D01*
G01X604301Y186942D02*
X600633Y204186D01*
G01X591213Y216235D02*
X589289Y215826D01*
G01X591364Y217494D02*
X589007Y216994D01*
G01X595949Y213961D02*
X591213Y216235D01*
G01X596772Y214897D02*
X591364Y217494D01*
G01X599821Y208001D02*
X595949Y213961D01*
G01X600949Y208469D02*
X596772Y214897D01*
G01X600071Y206827D02*
X599821Y208001D01*
G01X605429Y187409D02*
X600949Y208469D01*
G01X604301Y186942D02*
X600633Y204186D01*
G01X605429Y187409D02*
X600949Y208469D01*
G01X596537Y196015D02*
X597861Y189782D01*
G01X596733Y189315D02*
X595409Y195548D01*
G01X593592Y200548D02*
X596537Y196015D01*
G01X595409Y195548D02*
X592887Y199430D01*
G01X585815Y201568D02*
X593592Y200548D01*
G01X592887Y199430D02*
X585863Y200351D01*
G01X584882Y201370D02*
X585815Y201568D01*
G01X585863Y200351D02*
X585169Y200204D01*
G01X585863Y200351D02*
X585169Y200204D01*
G01X584882Y201370D02*
X585815Y201568D01*
G01X592887Y199430D02*
X585863Y200351D01*
G01X585815Y201568D02*
X593592Y200548D01*
G01X595409Y195548D02*
X592887Y199430D01*
G01X593592Y200548D02*
X596537Y196015D01*
G01X596733Y189315D02*
X595409Y195548D01*
G01X596537Y196015D02*
X597861Y189782D01*
G01X594056Y185730D02*
X597286Y183634D01*
G01X593577Y184610D02*
X596418Y182766D01*
G01X587722Y187228D02*
X594056Y185730D01*
G01X587708Y185998D02*
X593577Y184610D01*
G01X580807Y185757D02*
X587722Y187228D01*
G01X581057Y184583D02*
X587708Y185998D01*
G01X580757Y185746D02*
G02X580807Y185757I396J-1681D01*
G01X580726Y184355D02*
G02X581057Y184583I441J-287D01*
G01X593577Y184610D02*
X596418Y182766D01*
G01X594056Y185730D02*
X597286Y183634D01*
G01X587708Y185998D02*
X593577Y184610D01*
G01X587722Y187228D02*
X594056Y185730D01*
G01X581057Y184583D02*
X587708Y185998D01*
G01X580807Y185757D02*
X587722Y187228D01*
G01X580726Y184355D02*
G02X581057Y184583I441J-287D01*
G01X580757Y185746D02*
G02X580807Y185757I396J-1681D01*
G01X589628Y176929D02*
G03X589578Y176918I346J-1692D01*
G01X589878Y175755D02*
G03X589547Y175527I110J-515D01*
G01X593244Y177698D02*
X589628Y176929D01*
G01X593159Y176452D02*
X589878Y175755D01*
G01X596712Y176447D02*
X593244Y177697D01*
G01X598051Y175578D02*
X596712Y176447D01*
G01X589878Y175755D02*
G03X589547Y175527I110J-515D01*
G01X589628Y176929D02*
G03X589578Y176918I346J-1692D01*
G01X593159Y176452D02*
X589878Y175755D01*
G01X593244Y177698D02*
X589628Y176929D01*
G01X596712Y176447D02*
X593244Y177697D01*
G01X598051Y175578D02*
X596712Y176447D01*
G01X645411Y149547D02*
X641802Y150313D01*
G01X643784Y148665D02*
X641335Y149185D01*
G01X646140Y148164D02*
X643784Y148665D01*
G01X646267Y149364D02*
X645411Y149547D01*
G01X646140Y148164D02*
X643784Y148665D01*
G01X651713Y149364D02*
X646267D01*
G01X652211Y148164D02*
X646140D01*
G01X652578Y150229D02*
X651713Y149364D01*
G01X653076Y149029D02*
X652211Y148164D01*
G01X653848Y150229D02*
X652578D01*
G01X653984Y149029D02*
X653076D01*
G01X643784Y148665D02*
X641335Y149185D01*
G01X645411Y149547D02*
X641802Y150313D01*
G01X646140Y148164D02*
X643784Y148665D01*
G01X645411Y149547D02*
X641802Y150313D01*
G01X646267Y149364D02*
X645411Y149547D01*
G01X652211Y148164D02*
X646140D01*
G01X651713Y149364D02*
X646267D01*
G01X653076Y149029D02*
X652211Y148164D01*
G01X652578Y150229D02*
X651713Y149364D01*
G01X653984Y149029D02*
X653076D01*
G01X653848Y150229D02*
X652578D01*
G01X646021Y144882D02*
X651181D01*
G01X649487Y143682D02*
X645895D01*
G01X638633Y146450D02*
X646021Y144882D01*
G01X645895Y143682D02*
X638166Y145322D01*
G01X637627Y147104D02*
X638633Y146450D01*
G01X637627Y147104D02*
X638633Y146450D01*
G01X645895Y143682D02*
X638166Y145322D01*
G01X638633Y146450D02*
X646021Y144882D01*
G01X649487Y143682D02*
X645895D01*
G01X646021Y144882D02*
X651181D01*
G01X652583Y140780D02*
X653848D01*
G01X653081Y139580D02*
X653984D01*
G01X651586Y139783D02*
X652583Y140780D01*
G01X653081Y139580D02*
X653984D01*
G01X652084Y138583D02*
X653081Y139580D01*
G01X642075Y139783D02*
X651586D01*
G01X641948Y138583D02*
X652084D01*
G01X636897Y140883D02*
X642075Y139783D01*
G01X636429Y139755D02*
X641948Y138583D01*
G01X635381Y140436D02*
X636429Y139755D01*
G01X653081Y139580D02*
X653984D01*
G01X652583Y140780D02*
X653848D01*
G01X651586Y139783D02*
X652583Y140780D01*
G01X652084Y138583D02*
X653081Y139580D01*
G01X651586Y139783D02*
X652583Y140780D01*
G01X641948Y138583D02*
X652084D01*
G01X642075Y139783D02*
X651586D01*
G01X636429Y139755D02*
X641948Y138583D01*
G01X636897Y140883D02*
X642075Y139783D01*
G01X635381Y140436D02*
X636429Y139755D01*
G01X642084Y135368D02*
X640176Y135773D01*
G01X644428Y135367D02*
X642085D01*
G01X644428Y134167D02*
X641958D01*
G01X642084Y135368D02*
X640176Y135773D01*
G01X644428Y134167D02*
X641958D01*
G01X644428Y135367D02*
X642085D01*
G01X636152Y131805D02*
X644867D01*
G01Y130605D02*
X636026D01*
G01X635276Y131991D02*
X636152Y131805D01*
G01X635276Y131991D02*
X636152Y131805D01*
G01X644867Y130605D02*
X636026D01*
G01X636152Y131805D02*
X644867D01*
G01X646526Y125974D02*
X644406Y128094D01*
G01X646028Y124774D02*
X643908Y126894D01*
G01X650522Y125974D02*
X646526D01*
G01X650522Y124774D02*
X646028D01*
G01D02*
X643908Y126894D01*
G01X646526Y125974D02*
X644406Y128094D01*
G01X650522Y124774D02*
X646028D01*
G01X650522Y125974D02*
X646526D01*
G01X651612Y120900D02*
X644974D01*
G01X652110Y119700D02*
X644847D01*
G01X652594Y121882D02*
X651612Y120900D01*
G01X653092Y120682D02*
X652110Y119700D01*
G01X653848Y121882D02*
X652594D01*
G01X653984Y120682D02*
X653092D01*
G01X652110Y119700D02*
X644847D01*
G01X651612Y120900D02*
X644974D01*
G01X653092Y120682D02*
X652110Y119700D01*
G01X652594Y121882D02*
X651612Y120900D01*
G01X653984Y120682D02*
X653092D01*
G01X653848Y121882D02*
X652594D01*
G01X643066Y115935D02*
X650971D01*
G01Y114735D02*
X642939D01*
G01X637751Y117065D02*
X643066Y115935D01*
G01X637751Y117065D02*
X643066Y115935D01*
G01X650971Y114735D02*
X642939D01*
G01X643066Y115935D02*
X650971D01*
G54D12*
G01X6250Y-135162D02*
Y-152662D01*
G01X1228Y-135162D02*
X11272D01*
G01X20038Y-152662D02*
Y-135162D01*
G01Y-143620D02*
X21130Y-142162D01*
X22222Y-141287D01*
X23968Y-140996D01*
X25278Y-141287D01*
X26807Y-142454D01*
X27462Y-144204D01*
Y-152662D01*
G01X41250Y-140996D02*
Y-152662D01*
G01Y-136329D02*
X40813Y-136037D01*
Y-135454D01*
X41250Y-135162D01*
X41687Y-135454D01*
Y-136037D01*
X41250Y-136329D01*
G01X55475Y-150621D02*
X56567Y-151787D01*
X58095Y-152662D01*
X59405D01*
X60715Y-152079D01*
X61588Y-151204D01*
X62025Y-150038D01*
X61807Y-148287D01*
X60933Y-147412D01*
X57003Y-145662D01*
X56130Y-143620D01*
X56567Y-142162D01*
X57440Y-141287D01*
X58750Y-140996D01*
X60060Y-141287D01*
X61370Y-142162D01*
G01X90693Y-157037D02*
X92222Y-158204D01*
X93968Y-158495D01*
X95496Y-158204D01*
X96807Y-156746D01*
X97680Y-154704D01*
Y-140996D01*
G01Y-143329D02*
X96807Y-142162D01*
X95496Y-141287D01*
X93968Y-140996D01*
X92222Y-141579D01*
X91130Y-142745D01*
X90256Y-144787D01*
X89820Y-146829D01*
X90038Y-148579D01*
X90912Y-150621D01*
X92222Y-152079D01*
X93968Y-152662D01*
X95278Y-152370D01*
X96807Y-151204D01*
X97680Y-150038D01*
G01X107975Y-144787D02*
X114962D01*
X114307Y-142745D01*
X113215Y-141579D01*
X111687Y-140996D01*
X110158Y-141287D01*
X108848Y-142162D01*
X107975Y-144204D01*
X107538Y-145954D01*
Y-147704D01*
X107975Y-149454D01*
X109067Y-151204D01*
X110377Y-152370D01*
X111905Y-152662D01*
X113433Y-152079D01*
X114962Y-150329D01*
G01X125693Y-152662D02*
Y-140996D01*
G01Y-143329D02*
X126785Y-142162D01*
X127877Y-141287D01*
X129405Y-140996D01*
X130496Y-141287D01*
X131807Y-142162D01*
G01X142320Y-152662D02*
Y-135162D01*
G01Y-143912D02*
X143412Y-142162D01*
X144722Y-141287D01*
X146032Y-140996D01*
X147996Y-141579D01*
X149307Y-142745D01*
X150180Y-144787D01*
Y-147120D01*
X149743Y-149454D01*
X148870Y-151204D01*
X147342Y-152370D01*
X146032Y-152662D01*
X144722Y-152370D01*
X143412Y-151496D01*
X142320Y-150038D01*
G01X160475Y-144787D02*
X167462D01*
X166807Y-142745D01*
X165715Y-141579D01*
X164187Y-140996D01*
X162658Y-141287D01*
X161348Y-142162D01*
X160475Y-144204D01*
X160038Y-145954D01*
Y-147704D01*
X160475Y-149454D01*
X161567Y-151204D01*
X162877Y-152370D01*
X164405Y-152662D01*
X165933Y-152079D01*
X167462Y-150329D01*
G01X178193Y-152662D02*
Y-140996D01*
G01Y-143329D02*
X179285Y-142162D01*
X180377Y-141287D01*
X181905Y-140996D01*
X182996Y-141287D01*
X184307Y-142162D01*
G01X216250Y-140996D02*
Y-152662D01*
G01Y-136329D02*
X215813Y-136037D01*
Y-135454D01*
X216250Y-135162D01*
X216687Y-135454D01*
Y-136037D01*
X216250Y-136329D01*
G01X230475Y-150621D02*
X231567Y-151787D01*
X233095Y-152662D01*
X234405D01*
X235715Y-152079D01*
X236588Y-151204D01*
X237025Y-150038D01*
X236807Y-148287D01*
X235933Y-147412D01*
X232003Y-145662D01*
X231130Y-143620D01*
X231567Y-142162D01*
X232440Y-141287D01*
X233750Y-140996D01*
X235060Y-141287D01*
X236370Y-142162D01*
G01X265256Y-157037D02*
X266785Y-158204D01*
X268095Y-158495D01*
X269842Y-157912D01*
X271152Y-156454D01*
X271807Y-153828D01*
Y-140996D01*
G01Y-136329D02*
X271370Y-136037D01*
Y-135454D01*
X271807Y-135162D01*
X272243Y-135454D01*
Y-136037D01*
X271807Y-136329D01*
G01X282538Y-140996D02*
Y-149162D01*
X283412Y-151204D01*
X284722Y-152370D01*
X286250Y-152662D01*
X287778Y-152370D01*
X289088Y-151204D01*
X289962Y-149162D01*
G01Y-152662D02*
Y-140996D01*
G01X300475Y-150621D02*
X301567Y-151787D01*
X303095Y-152662D01*
X304405D01*
X305715Y-152079D01*
X306588Y-151204D01*
X307025Y-150038D01*
X306807Y-148287D01*
X305933Y-147412D01*
X302003Y-145662D01*
X301130Y-143620D01*
X301567Y-142162D01*
X302440Y-141287D01*
X303750Y-140996D01*
X305060Y-141287D01*
X306370Y-142162D01*
G01X321250Y-135162D02*
Y-152662D01*
G01X318193Y-140996D02*
X324307D01*
G01X354940Y-152662D02*
Y-137787D01*
X355377Y-136329D01*
X356250Y-135454D01*
X357560Y-135162D01*
X358870Y-135745D01*
X359525Y-137204D01*
G01X356905Y-142162D02*
X352538D01*
G01X373750Y-152662D02*
X372440Y-152370D01*
X371130Y-151204D01*
X370256Y-149162D01*
X369820Y-146829D01*
X370256Y-144495D01*
X371130Y-142454D01*
X372440Y-141287D01*
X373750Y-140996D01*
X375060Y-141287D01*
X376370Y-142454D01*
X377243Y-144495D01*
X377462Y-146829D01*
X377243Y-149162D01*
X376370Y-151204D01*
X375060Y-152370D01*
X373750Y-152662D01*
G01X388193D02*
Y-140996D01*
G01Y-143329D02*
X389285Y-142162D01*
X390377Y-141287D01*
X391905Y-140996D01*
X392996Y-141287D01*
X394307Y-142162D01*
G01X421665Y-157912D02*
X422975Y-158495D01*
X424722Y-157912D01*
X425813Y-156746D01*
X426687Y-155287D01*
X427996Y-150621D01*
X430835Y-140996D01*
G01X423848D02*
X427996Y-150621D01*
G01X443750Y-152662D02*
X442440Y-152370D01*
X441130Y-151204D01*
X440256Y-149162D01*
X439820Y-146829D01*
X440256Y-144495D01*
X441130Y-142454D01*
X442440Y-141287D01*
X443750Y-140996D01*
X445060Y-141287D01*
X446370Y-142454D01*
X447243Y-144495D01*
X447462Y-146829D01*
X447243Y-149162D01*
X446370Y-151204D01*
X445060Y-152370D01*
X443750Y-152662D01*
G01X457538Y-140996D02*
Y-149162D01*
X458412Y-151204D01*
X459722Y-152370D01*
X461250Y-152662D01*
X462778Y-152370D01*
X464088Y-151204D01*
X464962Y-149162D01*
G01Y-152662D02*
Y-140996D01*
G01X475693Y-152662D02*
Y-140996D01*
G01Y-143329D02*
X476785Y-142162D01*
X477877Y-141287D01*
X479405Y-140996D01*
X480496Y-141287D01*
X481807Y-142162D01*
G01X510693Y-152662D02*
Y-140996D01*
G01Y-143329D02*
X511785Y-142162D01*
X512877Y-141287D01*
X514405Y-140996D01*
X515496Y-141287D01*
X516807Y-142162D01*
G01X527975Y-144787D02*
X534962D01*
X534307Y-142745D01*
X533215Y-141579D01*
X531687Y-140996D01*
X530158Y-141287D01*
X528848Y-142162D01*
X527975Y-144204D01*
X527538Y-145954D01*
Y-147704D01*
X527975Y-149454D01*
X529067Y-151204D01*
X530377Y-152370D01*
X531905Y-152662D01*
X533433Y-152079D01*
X534962Y-150329D01*
G01X547440Y-152662D02*
Y-137787D01*
X547877Y-136329D01*
X548750Y-135454D01*
X550060Y-135162D01*
X551370Y-135745D01*
X552025Y-137204D01*
G01X549405Y-142162D02*
X545038D01*
G01X562975Y-144787D02*
X569962D01*
X569307Y-142745D01*
X568215Y-141579D01*
X566687Y-140996D01*
X565158Y-141287D01*
X563848Y-142162D01*
X562975Y-144204D01*
X562538Y-145954D01*
Y-147704D01*
X562975Y-149454D01*
X564067Y-151204D01*
X565377Y-152370D01*
X566905Y-152662D01*
X568433Y-152079D01*
X569962Y-150329D01*
G01X580693Y-152662D02*
Y-140996D01*
G01Y-143329D02*
X581785Y-142162D01*
X582877Y-141287D01*
X584405Y-140996D01*
X585496Y-141287D01*
X586807Y-142162D01*
G01X597975Y-144787D02*
X604962D01*
X604307Y-142745D01*
X603215Y-141579D01*
X601687Y-140996D01*
X600158Y-141287D01*
X598848Y-142162D01*
X597975Y-144204D01*
X597538Y-145954D01*
Y-147704D01*
X597975Y-149454D01*
X599067Y-151204D01*
X600377Y-152370D01*
X601905Y-152662D01*
X603433Y-152079D01*
X604962Y-150329D01*
G01X615038Y-152662D02*
Y-140996D01*
G01Y-143912D02*
X615912Y-142454D01*
X617222Y-141287D01*
X618968Y-140996D01*
X620496Y-141287D01*
X621807Y-142454D01*
X622462Y-144495D01*
Y-152662D01*
G01X639743Y-142454D02*
X638215Y-141287D01*
X636905Y-140996D01*
X635158Y-141579D01*
X633848Y-142745D01*
X632975Y-144787D01*
X632756Y-146829D01*
X632975Y-148871D01*
X633848Y-150621D01*
X635158Y-152079D01*
X636905Y-152662D01*
X638433Y-152079D01*
X639743Y-150912D01*
G01X650475Y-144787D02*
X657462D01*
X656807Y-142745D01*
X655715Y-141579D01*
X654187Y-140996D01*
X652658Y-141287D01*
X651348Y-142162D01*
X650475Y-144204D01*
X650038Y-145954D01*
Y-147704D01*
X650475Y-149454D01*
X651567Y-151204D01*
X652877Y-152370D01*
X654405Y-152662D01*
X655933Y-152079D01*
X657462Y-150329D01*
G01X688750Y-135162D02*
Y-152662D01*
G01X685693Y-140996D02*
X691807D01*
G01X706250Y-152662D02*
X704940Y-152370D01*
X703630Y-151204D01*
X702756Y-149162D01*
X702320Y-146829D01*
X702756Y-144495D01*
X703630Y-142454D01*
X704940Y-141287D01*
X706250Y-140996D01*
X707560Y-141287D01*
X708870Y-142454D01*
X709743Y-144495D01*
X709962Y-146829D01*
X709743Y-149162D01*
X708870Y-151204D01*
X707560Y-152370D01*
X706250Y-152662D01*
G01X739940D02*
Y-137787D01*
X740377Y-136329D01*
X741250Y-135454D01*
X742560Y-135162D01*
X743870Y-135745D01*
X744525Y-137204D01*
G01X741905Y-142162D02*
X737538D01*
G01X758750Y-140996D02*
Y-152662D01*
G01Y-136329D02*
X758313Y-136037D01*
Y-135454D01*
X758750Y-135162D01*
X759187Y-135454D01*
Y-136037D01*
X758750Y-136329D01*
G01X772538Y-152662D02*
Y-140996D01*
G01Y-143912D02*
X773412Y-142454D01*
X774722Y-141287D01*
X776468Y-140996D01*
X777996Y-141287D01*
X779307Y-142454D01*
X779962Y-144495D01*
Y-152662D01*
G01X797680Y-135162D02*
Y-152662D01*
G01Y-150038D02*
X796807Y-151496D01*
X795496Y-152370D01*
X793968Y-152662D01*
X792222Y-152079D01*
X790912Y-150621D01*
X790038Y-148871D01*
X789820Y-146829D01*
X790038Y-144787D01*
X790912Y-143037D01*
X792222Y-141579D01*
X793968Y-140996D01*
X795496Y-141287D01*
X796588Y-141871D01*
X797680Y-143037D01*
G01X828750Y-135162D02*
Y-152662D01*
G01X825693Y-140996D02*
X831807D01*
G01X842538Y-152662D02*
Y-135162D01*
G01Y-143620D02*
X843630Y-142162D01*
X844722Y-141287D01*
X846468Y-140996D01*
X847778Y-141287D01*
X849307Y-142454D01*
X849962Y-144204D01*
Y-152662D01*
G01X860475Y-144787D02*
X867462D01*
X866807Y-142745D01*
X865715Y-141579D01*
X864187Y-140996D01*
X862658Y-141287D01*
X861348Y-142162D01*
X860475Y-144204D01*
X860038Y-145954D01*
Y-147704D01*
X860475Y-149454D01*
X861567Y-151204D01*
X862877Y-152370D01*
X864405Y-152662D01*
X865933Y-152079D01*
X867462Y-150329D01*
G01X893947Y-152662D02*
Y-135162D01*
X898313D01*
X900060Y-136037D01*
X901370Y-137204D01*
X902462Y-138953D01*
X903335Y-140996D01*
X903553Y-143912D01*
X903335Y-146829D01*
X902462Y-148871D01*
X901370Y-150621D01*
X900060Y-151787D01*
X898313Y-152662D01*
X893947D01*
G01X911883D02*
Y-135162D01*
X917123D01*
X918870Y-136037D01*
X920180Y-138079D01*
X920617Y-140412D01*
X920180Y-142745D01*
X919088Y-144495D01*
X917123Y-145371D01*
X911883D01*
G01X951250Y-140996D02*
Y-152662D01*
G01Y-136329D02*
X950813Y-136037D01*
Y-135454D01*
X951250Y-135162D01*
X951687Y-135454D01*
Y-136037D01*
X951250Y-136329D01*
G01X962200Y-152662D02*
Y-140996D01*
G01Y-144204D02*
X962855Y-142745D01*
X963947Y-141579D01*
X965475Y-140996D01*
X967003Y-141579D01*
X968095Y-142745D01*
X968750Y-144204D01*
Y-152662D01*
G01Y-144204D02*
X969405Y-142745D01*
X970496Y-141579D01*
X972025Y-140996D01*
X973553Y-141579D01*
X974645Y-142745D01*
X975300Y-144495D01*
Y-152662D01*
G01X982320Y-158495D02*
Y-140996D01*
G01Y-143620D02*
X983412Y-142162D01*
X984503Y-141287D01*
X986250Y-140996D01*
X987778Y-141287D01*
X989307Y-142745D01*
X989962Y-144787D01*
X990180Y-146829D01*
X989962Y-148871D01*
X989307Y-150912D01*
X987996Y-152079D01*
X986250Y-152662D01*
X984722Y-152370D01*
X983193Y-151496D01*
X982320Y-150329D01*
G01X1000475Y-144787D02*
X1007462D01*
X1006807Y-142745D01*
X1005715Y-141579D01*
X1004187Y-140996D01*
X1002658Y-141287D01*
X1001348Y-142162D01*
X1000475Y-144204D01*
X1000038Y-145954D01*
Y-147704D01*
X1000475Y-149454D01*
X1001567Y-151204D01*
X1002877Y-152370D01*
X1004405Y-152662D01*
X1005933Y-152079D01*
X1007462Y-150329D01*
G01X1025180Y-135162D02*
Y-152662D01*
G01Y-150038D02*
X1024307Y-151496D01*
X1022996Y-152370D01*
X1021468Y-152662D01*
X1019722Y-152079D01*
X1018412Y-150621D01*
X1017538Y-148871D01*
X1017320Y-146829D01*
X1017538Y-144787D01*
X1018412Y-143037D01*
X1019722Y-141579D01*
X1021468Y-140996D01*
X1022996Y-141287D01*
X1024088Y-141871D01*
X1025180Y-143037D01*
G01X1042680Y-152662D02*
Y-140996D01*
G01Y-143037D02*
X1041807Y-141871D01*
X1040496Y-141287D01*
X1038968Y-140996D01*
X1037440Y-141579D01*
X1036130Y-142745D01*
X1035256Y-144495D01*
X1034820Y-146829D01*
X1035256Y-149162D01*
X1036130Y-150912D01*
X1037440Y-152079D01*
X1038968Y-152662D01*
X1040496Y-152370D01*
X1041807Y-151496D01*
X1042680Y-150329D01*
G01X1052538Y-152662D02*
Y-140996D01*
G01Y-143912D02*
X1053412Y-142454D01*
X1054722Y-141287D01*
X1056468Y-140996D01*
X1057996Y-141287D01*
X1059307Y-142454D01*
X1059962Y-144495D01*
Y-152662D01*
G01X1077243Y-142454D02*
X1075715Y-141287D01*
X1074405Y-140996D01*
X1072658Y-141579D01*
X1071348Y-142745D01*
X1070475Y-144787D01*
X1070256Y-146829D01*
X1070475Y-148871D01*
X1071348Y-150621D01*
X1072658Y-152079D01*
X1074405Y-152662D01*
X1075933Y-152079D01*
X1077243Y-150912D01*
G01X1087975Y-144787D02*
X1094962D01*
X1094307Y-142745D01*
X1093215Y-141579D01*
X1091687Y-140996D01*
X1090158Y-141287D01*
X1088848Y-142162D01*
X1087975Y-144204D01*
X1087538Y-145954D01*
Y-147704D01*
X1087975Y-149454D01*
X1089067Y-151204D01*
X1090377Y-152370D01*
X1091905Y-152662D01*
X1093433Y-152079D01*
X1094962Y-150329D01*
G01X1126250Y-135162D02*
Y-152662D01*
G01X1123193Y-140996D02*
X1129307D01*
G01X1140693Y-152662D02*
Y-140996D01*
G01Y-143329D02*
X1141785Y-142162D01*
X1142877Y-141287D01*
X1144405Y-140996D01*
X1145496Y-141287D01*
X1146807Y-142162D01*
G01X1165180Y-152662D02*
Y-140996D01*
G01Y-143037D02*
X1164307Y-141871D01*
X1162996Y-141287D01*
X1161468Y-140996D01*
X1159940Y-141579D01*
X1158630Y-142745D01*
X1157756Y-144495D01*
X1157320Y-146829D01*
X1157756Y-149162D01*
X1158630Y-150912D01*
X1159940Y-152079D01*
X1161468Y-152662D01*
X1162996Y-152370D01*
X1164307Y-151496D01*
X1165180Y-150329D01*
G01X1182243Y-142454D02*
X1180715Y-141287D01*
X1179405Y-140996D01*
X1177658Y-141579D01*
X1176348Y-142745D01*
X1175475Y-144787D01*
X1175256Y-146829D01*
X1175475Y-148871D01*
X1176348Y-150621D01*
X1177658Y-152079D01*
X1179405Y-152662D01*
X1180933Y-152079D01*
X1182243Y-150912D01*
G01X1192975Y-144787D02*
X1199962D01*
X1199307Y-142745D01*
X1198215Y-141579D01*
X1196687Y-140996D01*
X1195158Y-141287D01*
X1193848Y-142162D01*
X1192975Y-144204D01*
X1192538Y-145954D01*
Y-147704D01*
X1192975Y-149454D01*
X1194067Y-151204D01*
X1195377Y-152370D01*
X1196905Y-152662D01*
X1198433Y-152079D01*
X1199962Y-150329D01*
G01X1210475Y-150621D02*
X1211567Y-151787D01*
X1213095Y-152662D01*
X1214405D01*
X1215715Y-152079D01*
X1216588Y-151204D01*
X1217025Y-150038D01*
X1216807Y-148287D01*
X1215933Y-147412D01*
X1212003Y-145662D01*
X1211130Y-143620D01*
X1211567Y-142162D01*
X1212440Y-141287D01*
X1213750Y-140996D01*
X1215060Y-141287D01*
X1216370Y-142162D01*
G01X1248750Y-140996D02*
Y-152662D01*
G01Y-136329D02*
X1248313Y-136037D01*
Y-135454D01*
X1248750Y-135162D01*
X1249187Y-135454D01*
Y-136037D01*
X1248750Y-136329D01*
G01X1262538Y-152662D02*
Y-140996D01*
G01Y-143912D02*
X1263412Y-142454D01*
X1264722Y-141287D01*
X1266468Y-140996D01*
X1267996Y-141287D01*
X1269307Y-142454D01*
X1269962Y-144495D01*
Y-152662D01*
G01X1301250D02*
Y-135162D01*
G01X1322680Y-152662D02*
Y-140996D01*
G01Y-143037D02*
X1321807Y-141871D01*
X1320496Y-141287D01*
X1318968Y-140996D01*
X1317440Y-141579D01*
X1316130Y-142745D01*
X1315256Y-144495D01*
X1314820Y-146829D01*
X1315256Y-149162D01*
X1316130Y-150912D01*
X1317440Y-152079D01*
X1318968Y-152662D01*
X1320496Y-152370D01*
X1321807Y-151496D01*
X1322680Y-150329D01*
G01X1331665Y-157912D02*
X1332975Y-158495D01*
X1334722Y-157912D01*
X1335813Y-156746D01*
X1336687Y-155287D01*
X1337996Y-150621D01*
X1340835Y-140996D01*
G01X1333848D02*
X1337996Y-150621D01*
G01X1350475Y-144787D02*
X1357462D01*
X1356807Y-142745D01*
X1355715Y-141579D01*
X1354187Y-140996D01*
X1352658Y-141287D01*
X1351348Y-142162D01*
X1350475Y-144204D01*
X1350038Y-145954D01*
Y-147704D01*
X1350475Y-149454D01*
X1351567Y-151204D01*
X1352877Y-152370D01*
X1354405Y-152662D01*
X1355933Y-152079D01*
X1357462Y-150329D01*
G01X1368193Y-152662D02*
Y-140996D01*
G01Y-143329D02*
X1369285Y-142162D01*
X1370377Y-141287D01*
X1371905Y-140996D01*
X1372996Y-141287D01*
X1374307Y-142162D01*
G01X1401883Y-135162D02*
Y-152662D01*
X1410617D01*
G01X1418947Y-149162D02*
X1420256Y-151204D01*
X1422003Y-152370D01*
X1423968Y-152662D01*
X1425715Y-152370D01*
X1427462Y-150912D01*
X1428553Y-149162D01*
X1428772Y-147412D01*
X1428335Y-145371D01*
X1426807Y-143912D01*
X1425278Y-143329D01*
X1423313D01*
G01X1425278D02*
X1426588Y-142454D01*
X1427680Y-140996D01*
X1428117Y-139246D01*
X1427680Y-137495D01*
X1426588Y-136037D01*
X1424623Y-135162D01*
X1422658Y-135454D01*
X1420693Y-136621D01*
G01X1441250Y-153245D02*
X1440813Y-152954D01*
Y-152370D01*
X1441250Y-152079D01*
X1441687Y-152370D01*
Y-152954D01*
X1441250Y-153245D01*
G01X878818Y546266D02*
Y563766D01*
X883184D01*
X884931Y562891D01*
X886241Y561724D01*
X887333Y559975D01*
X888206Y557932D01*
X888424Y555016D01*
X888206Y552099D01*
X887333Y550057D01*
X886241Y548307D01*
X884931Y547141D01*
X883184Y546266D01*
X878818D01*
G01X896754D02*
Y563766D01*
X901994D01*
X903741Y562891D01*
X905051Y560849D01*
X905488Y558516D01*
X905051Y556183D01*
X903959Y554433D01*
X901994Y553557D01*
X896754D01*
G01X933501Y563766D02*
X938741D01*
G01X936121D02*
Y546266D01*
G01X933501D02*
X938741D01*
G01X947944D02*
Y563766D01*
X953621Y549183D01*
X959298Y563766D01*
Y546266D01*
G01X966754D02*
Y563766D01*
X971994D01*
X973741Y562891D01*
X975051Y560849D01*
X975488Y558516D01*
X975051Y556183D01*
X973959Y554433D01*
X971994Y553557D01*
X966754D01*
G01X992988Y546266D02*
X984254D01*
Y563766D01*
X992988D01*
G01X989494Y555308D02*
X984254D01*
G01X1001318Y546266D02*
Y563766D01*
X1005684D01*
X1007431Y562891D01*
X1008741Y561724D01*
X1009833Y559975D01*
X1010706Y557932D01*
X1010924Y555016D01*
X1010706Y552099D01*
X1009833Y550057D01*
X1008741Y548307D01*
X1007431Y547141D01*
X1005684Y546266D01*
X1001318D01*
G01X1018162D02*
X1023621Y563766D01*
X1029080Y546266D01*
G01X1027114Y552391D02*
X1020127D01*
G01X1036099Y546266D02*
Y563766D01*
X1046143Y546266D01*
Y563766D01*
G01X1063424Y562307D02*
X1062114Y563183D01*
X1060586Y563766D01*
X1058839D01*
X1056874Y562891D01*
X1055346Y561433D01*
X1054254Y559682D01*
X1053381Y556766D01*
X1053162Y554141D01*
X1053599Y551516D01*
X1054254Y549766D01*
X1055564Y548016D01*
X1057093Y546849D01*
X1058621Y546266D01*
X1060149D01*
X1061678Y546849D01*
X1062988Y547724D01*
X1064080Y548890D01*
G01X1080488Y546266D02*
X1071754D01*
Y563766D01*
X1080488D01*
G01X1076994Y555308D02*
X1071754D01*
G01X1111121Y563766D02*
Y546266D01*
G01X1106099Y563766D02*
X1116143D01*
G01X1123162Y546266D02*
X1128621Y563766D01*
X1134080Y546266D01*
G01X1132114Y552391D02*
X1125127D01*
G01X1147867Y555599D02*
X1148741Y556474D01*
X1149396Y557932D01*
X1149833Y559975D01*
X1149396Y561724D01*
X1148523Y562891D01*
X1146994Y563766D01*
X1141099D01*
Y546266D01*
X1148304D01*
X1149833Y547432D01*
X1150706Y549183D01*
X1151143Y551224D01*
X1150706Y553266D01*
X1149396Y555016D01*
X1147867Y555599D01*
X1141099D01*
G01X1159254Y563766D02*
Y546266D01*
X1167988D01*
G01X1185488D02*
X1176754D01*
Y563766D01*
X1185488D01*
G01X1181994Y555308D02*
X1176754D01*
G01X1198621Y545683D02*
X1198184Y545974D01*
Y546558D01*
X1198621Y546849D01*
X1199058Y546558D01*
Y545974D01*
X1198621Y545683D01*
G01Y553557D02*
X1198184Y553849D01*
Y554433D01*
X1198621Y554724D01*
X1199058Y554433D01*
Y553849D01*
X1198621Y553557D01*
G01X1229254Y563766D02*
Y546266D01*
X1237988D01*
G01X1246318Y549766D02*
X1247627Y547724D01*
X1249374Y546558D01*
X1251339Y546266D01*
X1253086Y546558D01*
X1254833Y548016D01*
X1255924Y549766D01*
X1256143Y551516D01*
X1255706Y553557D01*
X1254178Y555016D01*
X1252649Y555599D01*
X1250684D01*
G01X1252649D02*
X1253959Y556474D01*
X1255051Y557932D01*
X1255488Y559682D01*
X1255051Y561433D01*
X1253959Y562891D01*
X1251994Y563766D01*
X1250029Y563474D01*
X1248064Y562307D01*
G01X924768Y407083D02*
X934374Y419916D01*
G01X929571Y422249D02*
Y404749D01*
G01X934374Y407083D02*
X924768Y419916D01*
G01X923021Y413499D02*
X936121D01*
G01X947071Y407666D02*
X948599Y407958D01*
X950346Y408832D01*
X951438Y410290D01*
X951874Y412333D01*
X951438Y414374D01*
X950128Y416124D01*
X948163Y416999D01*
X945979D01*
X944669Y417583D01*
X943577Y419041D01*
X943141Y421082D01*
X943796Y423124D01*
X945324Y424583D01*
X947071Y425166D01*
X948817Y424583D01*
X950346Y423124D01*
X951001Y421082D01*
X950564Y419041D01*
X949473Y417583D01*
X948163Y416999D01*
X945979D01*
X944014Y416124D01*
X942704Y414374D01*
X942268Y412333D01*
X942704Y410290D01*
X943796Y408832D01*
X945543Y407958D01*
X947071Y407666D01*
G01X964571D02*
X966099Y407958D01*
X967846Y408832D01*
X968938Y410290D01*
X969374Y412333D01*
X968938Y414374D01*
X967628Y416124D01*
X965663Y416999D01*
X963479D01*
X962169Y417583D01*
X961077Y419041D01*
X960641Y421082D01*
X961296Y423124D01*
X962824Y424583D01*
X964571Y425166D01*
X966317Y424583D01*
X967846Y423124D01*
X968501Y421082D01*
X968064Y419041D01*
X966973Y417583D01*
X965663Y416999D01*
X963479D01*
X961514Y416124D01*
X960204Y414374D01*
X959768Y412333D01*
X960204Y410290D01*
X961296Y408832D01*
X963043Y407958D01*
X964571Y407666D01*
G01X982071Y407083D02*
X981634Y407374D01*
Y407958D01*
X982071Y408249D01*
X982508Y407958D01*
Y407374D01*
X982071Y407083D01*
G01X999571Y425166D02*
X997824Y424583D01*
X996514Y423124D01*
X995641Y421375D01*
X994986Y419041D01*
X994768Y416416D01*
X994986Y413791D01*
X995641Y411457D01*
X996514Y409707D01*
X997824Y408249D01*
X999571Y407666D01*
X1001317Y408249D01*
X1002628Y409707D01*
X1003501Y411457D01*
X1004156Y413791D01*
X1004374Y416416D01*
X1004156Y419041D01*
X1003501Y421375D01*
X1002628Y423124D01*
X1001317Y424583D01*
X999571Y425166D01*
G01X929571Y373016D02*
Y390516D01*
X926951Y387016D01*
G01Y373016D02*
X932191D01*
G01X947071Y390516D02*
X945324Y389933D01*
X944014Y388474D01*
X943141Y386725D01*
X942486Y384391D01*
X942268Y381766D01*
X942486Y379141D01*
X943141Y376807D01*
X944014Y375057D01*
X945324Y373599D01*
X947071Y373016D01*
X948817Y373599D01*
X950128Y375057D01*
X951001Y376807D01*
X951656Y379141D01*
X951874Y381766D01*
X951656Y384391D01*
X951001Y386725D01*
X950128Y388474D01*
X948817Y389933D01*
X947071Y390516D01*
G01X964571D02*
X962824Y389933D01*
X961514Y388474D01*
X960641Y386725D01*
X959986Y384391D01*
X959768Y381766D01*
X959986Y379141D01*
X960641Y376807D01*
X961514Y375057D01*
X962824Y373599D01*
X964571Y373016D01*
X966317Y373599D01*
X967628Y375057D01*
X968501Y376807D01*
X969156Y379141D01*
X969374Y381766D01*
X969156Y384391D01*
X968501Y386725D01*
X967628Y388474D01*
X966317Y389933D01*
X964571Y390516D01*
G01X982071Y372433D02*
X981634Y372724D01*
Y373308D01*
X982071Y373599D01*
X982508Y373308D01*
Y372724D01*
X982071Y372433D01*
G01X999571Y390516D02*
X997824Y389933D01*
X996514Y388474D01*
X995641Y386725D01*
X994986Y384391D01*
X994768Y381766D01*
X994986Y379141D01*
X995641Y376807D01*
X996514Y375057D01*
X997824Y373599D01*
X999571Y373016D01*
X1001317Y373599D01*
X1002628Y375057D01*
X1003501Y376807D01*
X1004156Y379141D01*
X1004374Y381766D01*
X1004156Y384391D01*
X1003501Y386725D01*
X1002628Y388474D01*
X1001317Y389933D01*
X999571Y390516D01*
G01X924768Y476383D02*
X934374Y489216D01*
G01X929571Y491549D02*
Y474049D01*
G01X934374Y476383D02*
X924768Y489216D01*
G01X923021Y482799D02*
X936121D01*
G01X947071Y476966D02*
X948599Y477258D01*
X950346Y478132D01*
X951438Y479590D01*
X951874Y481633D01*
X951438Y483674D01*
X950128Y485424D01*
X948163Y486299D01*
X945979D01*
X944669Y486883D01*
X943577Y488341D01*
X943141Y490382D01*
X943796Y492424D01*
X945324Y493883D01*
X947071Y494466D01*
X948817Y493883D01*
X950346Y492424D01*
X951001Y490382D01*
X950564Y488341D01*
X949473Y486883D01*
X948163Y486299D01*
X945979D01*
X944014Y485424D01*
X942704Y483674D01*
X942268Y481633D01*
X942704Y479590D01*
X943796Y478132D01*
X945543Y477258D01*
X947071Y476966D01*
G01X959768Y480466D02*
X961077Y478424D01*
X962824Y477258D01*
X964789Y476966D01*
X966536Y477258D01*
X968283Y478716D01*
X969374Y480466D01*
X969593Y482216D01*
X969156Y484257D01*
X967628Y485716D01*
X966099Y486299D01*
X964134D01*
G01X966099D02*
X967409Y487174D01*
X968501Y488632D01*
X968938Y490382D01*
X968501Y492133D01*
X967409Y493591D01*
X965444Y494466D01*
X963479Y494174D01*
X961514Y493007D01*
G01X982071Y476383D02*
X981634Y476674D01*
Y477258D01*
X982071Y477549D01*
X982508Y477258D01*
Y476674D01*
X982071Y476383D01*
G01X999571Y494466D02*
X997824Y493883D01*
X996514Y492424D01*
X995641Y490675D01*
X994986Y488341D01*
X994768Y485716D01*
X994986Y483091D01*
X995641Y480757D01*
X996514Y479007D01*
X997824Y477549D01*
X999571Y476966D01*
X1001317Y477549D01*
X1002628Y479007D01*
X1003501Y480757D01*
X1004156Y483091D01*
X1004374Y485716D01*
X1004156Y488341D01*
X1003501Y490675D01*
X1002628Y492424D01*
X1001317Y493883D01*
X999571Y494466D01*
G01X924768Y441733D02*
X934374Y454566D01*
G01X929571Y456899D02*
Y439399D01*
G01X934374Y441733D02*
X924768Y454566D01*
G01X923021Y448149D02*
X936121D01*
G01X947071Y442316D02*
X948599Y442608D01*
X950346Y443482D01*
X951438Y444940D01*
X951874Y446983D01*
X951438Y449024D01*
X950128Y450774D01*
X948163Y451649D01*
X945979D01*
X944669Y452233D01*
X943577Y453691D01*
X943141Y455732D01*
X943796Y457774D01*
X945324Y459233D01*
X947071Y459816D01*
X948817Y459233D01*
X950346Y457774D01*
X951001Y455732D01*
X950564Y453691D01*
X949473Y452233D01*
X948163Y451649D01*
X945979D01*
X944014Y450774D01*
X942704Y449024D01*
X942268Y446983D01*
X942704Y444940D01*
X943796Y443482D01*
X945543Y442608D01*
X947071Y442316D01*
G01X959768Y444940D02*
X961077Y443482D01*
X962606Y442608D01*
X964571Y442316D01*
X966536Y442899D01*
X968064Y444066D01*
X969156Y446107D01*
X969374Y448441D01*
X968938Y450774D01*
X967846Y452233D01*
X966317Y453399D01*
X964789Y453691D01*
X963261Y453399D01*
X961296Y452233D01*
X961951Y459816D01*
X967846D01*
G01X982071Y441733D02*
X981634Y442024D01*
Y442608D01*
X982071Y442899D01*
X982508Y442608D01*
Y442024D01*
X982071Y441733D01*
G01X999571Y459816D02*
X997824Y459233D01*
X996514Y457774D01*
X995641Y456025D01*
X994986Y453691D01*
X994768Y451066D01*
X994986Y448441D01*
X995641Y446107D01*
X996514Y444357D01*
X997824Y442899D01*
X999571Y442316D01*
X1001317Y442899D01*
X1002628Y444357D01*
X1003501Y446107D01*
X1004156Y448441D01*
X1004374Y451066D01*
X1004156Y453691D01*
X1003501Y456025D01*
X1002628Y457774D01*
X1001317Y459233D01*
X999571Y459816D01*
G01X900701Y529116D02*
X905941D01*
G01X903321D02*
Y511616D01*
G01X900701D02*
X905941D01*
G01X915144D02*
Y529116D01*
X920821Y514533D01*
X926498Y529116D01*
Y511616D01*
G01X933954D02*
Y529116D01*
X939194D01*
X940941Y528241D01*
X942251Y526199D01*
X942688Y523866D01*
X942251Y521533D01*
X941159Y519783D01*
X939194Y518907D01*
X933954D01*
G01X954729Y505783D02*
X952546Y508699D01*
X951454Y511616D01*
Y523282D01*
X952546Y526199D01*
X954729Y529116D01*
G01X973321Y511616D02*
X971574Y511908D01*
X970046Y513074D01*
X968736Y514824D01*
X967862Y516866D01*
X967426Y519199D01*
Y521533D01*
X967862Y523866D01*
X968736Y525908D01*
X970046Y527657D01*
X971574Y528824D01*
X973321Y529116D01*
X975067Y528824D01*
X976596Y527657D01*
X977906Y525908D01*
X978780Y523866D01*
X979216Y521533D01*
Y519199D01*
X978780Y516866D01*
X977906Y514824D01*
X976596Y513074D01*
X975067Y511908D01*
X973321Y511616D01*
G01X987109D02*
Y529116D01*
G01Y520658D02*
X988201Y522116D01*
X989293Y522991D01*
X991039Y523282D01*
X992349Y522991D01*
X993878Y521824D01*
X994533Y520074D01*
Y511616D01*
G01X1001771D02*
Y523282D01*
G01Y520074D02*
X1002426Y521533D01*
X1003518Y522699D01*
X1005046Y523282D01*
X1006574Y522699D01*
X1007666Y521533D01*
X1008321Y520074D01*
Y511616D01*
G01Y520074D02*
X1008976Y521533D01*
X1010067Y522699D01*
X1011596Y523282D01*
X1013124Y522699D01*
X1014216Y521533D01*
X1014871Y519783D01*
Y511616D01*
G01X1026913Y505783D02*
X1029096Y508699D01*
X1030188Y511616D01*
Y523282D01*
X1029096Y526199D01*
X1026913Y529116D01*
G01X1115521D02*
X1118577Y511616D01*
X1122071Y529116D01*
X1125564Y511616D01*
X1128621Y529116D01*
G01X1136951D02*
X1142191D01*
G01X1139571D02*
Y511616D01*
G01X1136951D02*
X1142191D01*
G01X1152268D02*
Y529116D01*
X1156634D01*
X1158381Y528241D01*
X1159691Y527074D01*
X1160783Y525325D01*
X1161656Y523282D01*
X1161874Y520366D01*
X1161656Y517449D01*
X1160783Y515407D01*
X1159691Y513657D01*
X1158381Y512491D01*
X1156634Y511616D01*
X1152268D01*
G01X1174571Y529116D02*
Y511616D01*
G01X1169549Y529116D02*
X1179593D01*
G01X1187486Y511616D02*
Y529116D01*
G01X1196656D02*
Y511616D01*
G01Y520366D02*
X1187486D01*
G01X1208479Y505783D02*
X1206296Y508699D01*
X1205204Y511616D01*
Y523282D01*
X1206296Y526199D01*
X1208479Y529116D01*
G01X1220521Y511616D02*
Y523282D01*
G01Y520074D02*
X1221176Y521533D01*
X1222268Y522699D01*
X1223796Y523282D01*
X1225324Y522699D01*
X1226416Y521533D01*
X1227071Y520074D01*
Y511616D01*
G01Y520074D02*
X1227726Y521533D01*
X1228817Y522699D01*
X1230346Y523282D01*
X1231874Y522699D01*
X1232966Y521533D01*
X1233621Y519783D01*
Y511616D01*
G01X1244571Y523282D02*
Y511616D01*
G01Y527949D02*
X1244134Y528241D01*
Y528824D01*
X1244571Y529116D01*
X1245008Y528824D01*
Y528241D01*
X1244571Y527949D01*
G01X1262071Y511616D02*
Y529116D01*
G01X1276296Y513657D02*
X1277388Y512491D01*
X1278916Y511616D01*
X1280226D01*
X1281536Y512199D01*
X1282409Y513074D01*
X1282846Y514240D01*
X1282628Y515991D01*
X1281754Y516866D01*
X1277824Y518616D01*
X1276951Y520658D01*
X1277388Y522116D01*
X1278261Y522991D01*
X1279571Y523282D01*
X1280881Y522991D01*
X1282191Y522116D01*
G01X1298163Y505783D02*
X1300346Y508699D01*
X1301438Y511616D01*
Y523282D01*
X1300346Y526199D01*
X1298163Y529116D01*
G01X1152268Y411166D02*
X1153577Y409124D01*
X1155324Y407958D01*
X1157289Y407666D01*
X1159036Y407958D01*
X1160783Y409416D01*
X1161874Y411166D01*
X1162093Y412916D01*
X1161656Y414957D01*
X1160128Y416416D01*
X1158599Y416999D01*
X1156634D01*
G01X1158599D02*
X1159909Y417874D01*
X1161001Y419332D01*
X1161438Y421082D01*
X1161001Y422833D01*
X1159909Y424291D01*
X1157944Y425166D01*
X1155979Y424874D01*
X1154014Y423707D01*
G01X1174571Y407083D02*
X1174134Y407374D01*
Y407958D01*
X1174571Y408249D01*
X1175008Y407958D01*
Y407374D01*
X1174571Y407083D01*
G01X1187268Y410290D02*
X1188577Y408832D01*
X1190106Y407958D01*
X1192071Y407666D01*
X1194036Y408249D01*
X1195564Y409416D01*
X1196656Y411457D01*
X1196874Y413791D01*
X1196438Y416124D01*
X1195346Y417583D01*
X1193817Y418749D01*
X1192289Y419041D01*
X1190761Y418749D01*
X1188796Y417583D01*
X1189451Y425166D01*
X1195346D01*
G01X1205641Y407083D02*
X1213501Y425166D01*
G01X1229691Y407666D02*
Y425166D01*
X1221612Y412624D01*
X1232530D01*
G01X1244571Y407083D02*
X1244134Y407374D01*
Y407958D01*
X1244571Y408249D01*
X1245008Y407958D01*
Y407374D01*
X1244571Y407083D01*
G01X1262071Y425166D02*
X1260324Y424583D01*
X1259014Y423124D01*
X1258141Y421375D01*
X1257486Y419041D01*
X1257268Y416416D01*
X1257486Y413791D01*
X1258141Y411457D01*
X1259014Y409707D01*
X1260324Y408249D01*
X1262071Y407666D01*
X1263817Y408249D01*
X1265128Y409707D01*
X1266001Y411457D01*
X1266656Y413791D01*
X1266874Y416416D01*
X1266656Y419041D01*
X1266001Y421375D01*
X1265128Y423124D01*
X1263817Y424583D01*
X1262071Y425166D01*
G01X1159691Y373016D02*
Y390516D01*
X1151612Y377974D01*
X1162530D01*
G01X1174571Y372433D02*
X1174134Y372724D01*
Y373308D01*
X1174571Y373599D01*
X1175008Y373308D01*
Y372724D01*
X1174571Y372433D01*
G01X1192071Y390516D02*
X1190324Y389933D01*
X1189014Y388474D01*
X1188141Y386725D01*
X1187486Y384391D01*
X1187268Y381766D01*
X1187486Y379141D01*
X1188141Y376807D01*
X1189014Y375057D01*
X1190324Y373599D01*
X1192071Y373016D01*
X1193817Y373599D01*
X1195128Y375057D01*
X1196001Y376807D01*
X1196656Y379141D01*
X1196874Y381766D01*
X1196656Y384391D01*
X1196001Y386725D01*
X1195128Y388474D01*
X1193817Y389933D01*
X1192071Y390516D01*
G01X1205641Y372433D02*
X1213501Y390516D01*
G01X1227071Y373016D02*
X1228599Y373308D01*
X1230346Y374182D01*
X1231438Y375640D01*
X1231874Y377683D01*
X1231438Y379724D01*
X1230128Y381474D01*
X1228163Y382349D01*
X1225979D01*
X1224669Y382933D01*
X1223577Y384391D01*
X1223141Y386432D01*
X1223796Y388474D01*
X1225324Y389933D01*
X1227071Y390516D01*
X1228817Y389933D01*
X1230346Y388474D01*
X1231001Y386432D01*
X1230564Y384391D01*
X1229473Y382933D01*
X1228163Y382349D01*
X1225979D01*
X1224014Y381474D01*
X1222704Y379724D01*
X1222268Y377683D01*
X1222704Y375640D01*
X1223796Y374182D01*
X1225543Y373308D01*
X1227071Y373016D01*
G01X1244571Y372433D02*
X1244134Y372724D01*
Y373308D01*
X1244571Y373599D01*
X1245008Y373308D01*
Y372724D01*
X1244571Y372433D01*
G01X1262071Y390516D02*
X1260324Y389933D01*
X1259014Y388474D01*
X1258141Y386725D01*
X1257486Y384391D01*
X1257268Y381766D01*
X1257486Y379141D01*
X1258141Y376807D01*
X1259014Y375057D01*
X1260324Y373599D01*
X1262071Y373016D01*
X1263817Y373599D01*
X1265128Y375057D01*
X1266001Y376807D01*
X1266656Y379141D01*
X1266874Y381766D01*
X1266656Y384391D01*
X1266001Y386725D01*
X1265128Y388474D01*
X1263817Y389933D01*
X1262071Y390516D01*
G01X1143518Y480466D02*
X1144827Y478424D01*
X1146574Y477258D01*
X1148539Y476966D01*
X1150286Y477258D01*
X1152033Y478716D01*
X1153124Y480466D01*
X1153343Y482216D01*
X1152906Y484257D01*
X1151378Y485716D01*
X1149849Y486299D01*
X1147884D01*
G01X1149849D02*
X1151159Y487174D01*
X1152251Y488632D01*
X1152688Y490382D01*
X1152251Y492133D01*
X1151159Y493591D01*
X1149194Y494466D01*
X1147229Y494174D01*
X1145264Y493007D01*
G01X1165821Y476383D02*
X1165384Y476674D01*
Y477258D01*
X1165821Y477549D01*
X1166258Y477258D01*
Y476674D01*
X1165821Y476383D01*
G01X1182884Y476966D02*
X1183321Y480757D01*
X1183976Y483966D01*
X1184849Y486883D01*
X1185941Y490091D01*
X1187688Y494466D01*
X1178954D01*
G01X1196018Y479590D02*
X1197327Y478132D01*
X1198856Y477258D01*
X1200821Y476966D01*
X1202786Y477549D01*
X1204314Y478716D01*
X1205406Y480757D01*
X1205624Y483091D01*
X1205188Y485424D01*
X1204096Y486883D01*
X1202567Y488049D01*
X1201039Y488341D01*
X1199511Y488049D01*
X1197546Y486883D01*
X1198201Y494466D01*
X1204096D01*
G01X1214391Y476383D02*
X1222251Y494466D01*
G01X1231018Y480466D02*
X1232327Y478424D01*
X1234074Y477258D01*
X1236039Y476966D01*
X1237786Y477258D01*
X1239533Y478716D01*
X1240624Y480466D01*
X1240843Y482216D01*
X1240406Y484257D01*
X1238878Y485716D01*
X1237349Y486299D01*
X1235384D01*
G01X1237349D02*
X1238659Y487174D01*
X1239751Y488632D01*
X1240188Y490382D01*
X1239751Y492133D01*
X1238659Y493591D01*
X1236694Y494466D01*
X1234729Y494174D01*
X1232764Y493007D01*
G01X1253321Y476383D02*
X1252884Y476674D01*
Y477258D01*
X1253321Y477549D01*
X1253758Y477258D01*
Y476674D01*
X1253321Y476383D01*
G01X1266018Y479590D02*
X1267327Y478132D01*
X1268856Y477258D01*
X1270821Y476966D01*
X1272786Y477549D01*
X1274314Y478716D01*
X1275406Y480757D01*
X1275624Y483091D01*
X1275188Y485424D01*
X1274096Y486883D01*
X1272567Y488049D01*
X1271039Y488341D01*
X1269511Y488049D01*
X1267546Y486883D01*
X1268201Y494466D01*
X1274096D01*
G01X1152268Y444940D02*
X1153577Y443482D01*
X1155106Y442608D01*
X1157071Y442316D01*
X1159036Y442899D01*
X1160564Y444066D01*
X1161656Y446107D01*
X1161874Y448441D01*
X1161438Y450774D01*
X1160346Y452233D01*
X1158817Y453399D01*
X1157289Y453691D01*
X1155761Y453399D01*
X1153796Y452233D01*
X1154451Y459816D01*
X1160346D01*
G01X1174571Y441733D02*
X1174134Y442024D01*
Y442608D01*
X1174571Y442899D01*
X1175008Y442608D01*
Y442024D01*
X1174571Y441733D01*
G01X1187268Y444940D02*
X1188577Y443482D01*
X1190106Y442608D01*
X1192071Y442316D01*
X1194036Y442899D01*
X1195564Y444066D01*
X1196656Y446107D01*
X1196874Y448441D01*
X1196438Y450774D01*
X1195346Y452233D01*
X1193817Y453399D01*
X1192289Y453691D01*
X1190761Y453399D01*
X1188796Y452233D01*
X1189451Y459816D01*
X1195346D01*
G01X1205641Y441733D02*
X1213501Y459816D01*
G01X1226634Y442316D02*
X1227071Y446107D01*
X1227726Y449316D01*
X1228599Y452233D01*
X1229691Y455441D01*
X1231438Y459816D01*
X1222704D01*
G01X1244571Y441733D02*
X1244134Y442024D01*
Y442608D01*
X1244571Y442899D01*
X1245008Y442608D01*
Y442024D01*
X1244571Y441733D01*
G01X1257268Y444940D02*
X1258577Y443482D01*
X1260106Y442608D01*
X1262071Y442316D01*
X1264036Y442899D01*
X1265564Y444066D01*
X1266656Y446107D01*
X1266874Y448441D01*
X1266438Y450774D01*
X1265346Y452233D01*
X1263817Y453399D01*
X1262289Y453691D01*
X1260761Y453399D01*
X1258796Y452233D01*
X1259451Y459816D01*
X1265346D01*
G01X1406018Y407666D02*
Y425166D01*
X1410384D01*
X1412131Y424291D01*
X1413441Y423124D01*
X1414533Y421375D01*
X1415406Y419332D01*
X1415624Y416416D01*
X1415406Y413499D01*
X1414533Y411457D01*
X1413441Y409707D01*
X1412131Y408541D01*
X1410384Y407666D01*
X1406018D01*
G01X1423954D02*
Y425166D01*
X1429194D01*
X1430941Y424291D01*
X1432251Y422249D01*
X1432688Y419916D01*
X1432251Y417583D01*
X1431159Y415833D01*
X1429194Y414957D01*
X1423954D01*
G01X1406018Y373016D02*
Y390516D01*
X1410384D01*
X1412131Y389641D01*
X1413441Y388474D01*
X1414533Y386725D01*
X1415406Y384682D01*
X1415624Y381766D01*
X1415406Y378849D01*
X1414533Y376807D01*
X1413441Y375057D01*
X1412131Y373891D01*
X1410384Y373016D01*
X1406018D01*
G01X1423954D02*
Y390516D01*
X1429194D01*
X1430941Y389641D01*
X1432251Y387599D01*
X1432688Y385266D01*
X1432251Y382933D01*
X1431159Y381183D01*
X1429194Y380307D01*
X1423954D01*
G01X1406018Y476966D02*
Y494466D01*
X1410384D01*
X1412131Y493591D01*
X1413441Y492424D01*
X1414533Y490675D01*
X1415406Y488632D01*
X1415624Y485716D01*
X1415406Y482799D01*
X1414533Y480757D01*
X1413441Y479007D01*
X1412131Y477841D01*
X1410384Y476966D01*
X1406018D01*
G01X1423954D02*
Y494466D01*
X1429194D01*
X1430941Y493591D01*
X1432251Y491549D01*
X1432688Y489216D01*
X1432251Y486883D01*
X1431159Y485133D01*
X1429194Y484257D01*
X1423954D01*
G01X1406018Y442316D02*
Y459816D01*
X1410384D01*
X1412131Y458941D01*
X1413441Y457774D01*
X1414533Y456025D01*
X1415406Y453982D01*
X1415624Y451066D01*
X1415406Y448149D01*
X1414533Y446107D01*
X1413441Y444357D01*
X1412131Y443191D01*
X1410384Y442316D01*
X1406018D01*
G01X1423954D02*
Y459816D01*
X1429194D01*
X1430941Y458941D01*
X1432251Y456899D01*
X1432688Y454566D01*
X1432251Y452233D01*
X1431159Y450483D01*
X1429194Y449607D01*
X1423954D01*
G01X1393321Y529116D02*
Y511616D01*
G01X1388299Y529116D02*
X1398343D01*
G01X1410821Y511616D02*
Y519491D01*
X1406454Y529116D01*
G01X1415188D02*
X1410821Y519491D01*
G01X1423954Y511616D02*
Y529116D01*
X1429194D01*
X1430941Y528241D01*
X1432251Y526199D01*
X1432688Y523866D01*
X1432251Y521533D01*
X1431159Y519783D01*
X1429194Y518907D01*
X1423954D01*
G01X1450188Y511616D02*
X1441454D01*
Y529116D01*
X1450188D01*
G01X1446694Y520658D02*
X1441454D01*
G01X1493954Y511616D02*
Y529116D01*
X1499413D01*
X1501159Y528241D01*
X1502251Y527074D01*
X1502688Y524741D01*
X1502251Y522407D01*
X1500941Y520949D01*
X1499413Y520074D01*
X1493954D01*
G01X1499413D02*
X1502688Y511616D01*
G01X1512546Y519491D02*
X1519533D01*
X1518878Y521533D01*
X1517786Y522699D01*
X1516258Y523282D01*
X1514729Y522991D01*
X1513419Y522116D01*
X1512546Y520074D01*
X1512109Y518324D01*
Y516574D01*
X1512546Y514824D01*
X1513638Y513074D01*
X1514948Y511908D01*
X1516476Y511616D01*
X1518004Y512199D01*
X1519533Y513949D01*
G01X1532011Y511616D02*
Y526491D01*
X1532448Y527949D01*
X1533321Y528824D01*
X1534631Y529116D01*
X1535941Y528533D01*
X1536596Y527074D01*
G01X1533976Y522116D02*
X1529609D01*
G01X1550821Y511033D02*
X1550384Y511324D01*
Y511908D01*
X1550821Y512199D01*
X1551258Y511908D01*
Y511324D01*
X1550821Y511033D01*
G01X1581454Y511616D02*
Y529116D01*
X1586694D01*
X1588441Y528241D01*
X1589751Y526199D01*
X1590188Y523866D01*
X1589751Y521533D01*
X1588659Y519783D01*
X1586694Y518907D01*
X1581454D01*
G01X1603321Y511616D02*
Y529116D01*
G01X1624751Y511616D02*
Y523282D01*
G01Y521241D02*
X1623878Y522407D01*
X1622567Y522991D01*
X1621039Y523282D01*
X1619511Y522699D01*
X1618201Y521533D01*
X1617327Y519783D01*
X1616891Y517449D01*
X1617327Y515116D01*
X1618201Y513366D01*
X1619511Y512199D01*
X1621039Y511616D01*
X1622567Y511908D01*
X1623878Y512782D01*
X1624751Y513949D01*
G01X1634609Y511616D02*
Y523282D01*
G01Y520366D02*
X1635483Y521824D01*
X1636793Y522991D01*
X1638539Y523282D01*
X1640067Y522991D01*
X1641378Y521824D01*
X1642033Y519783D01*
Y511616D01*
G01X1652546Y519491D02*
X1659533D01*
X1658878Y521533D01*
X1657786Y522699D01*
X1656258Y523282D01*
X1654729Y522991D01*
X1653419Y522116D01*
X1652546Y520074D01*
X1652109Y518324D01*
Y516574D01*
X1652546Y514824D01*
X1653638Y513074D01*
X1654948Y511908D01*
X1656476Y511616D01*
X1658004Y512199D01*
X1659533Y513949D01*
G01X1537704Y425166D02*
Y407666D01*
X1546438D01*
G01X1555423Y422249D02*
X1556733Y423999D01*
X1558261Y424874D01*
X1560008Y425166D01*
X1562191Y424583D01*
X1563719Y423124D01*
X1564156Y421375D01*
X1563938Y419624D01*
X1563064Y418166D01*
X1558698Y415249D01*
X1556733Y413208D01*
X1555423Y410290D01*
X1554986Y407666D01*
X1564156D01*
G01X1573141Y407083D02*
X1581001Y425166D01*
G01X1590204D02*
Y407666D01*
X1598938D01*
G01X1614691D02*
Y425166D01*
X1606612Y412624D01*
X1617530D01*
G01X1537704Y390516D02*
Y373016D01*
X1546438D01*
G01X1555423Y387599D02*
X1556733Y389349D01*
X1558261Y390224D01*
X1560008Y390516D01*
X1562191Y389933D01*
X1563719Y388474D01*
X1564156Y386725D01*
X1563938Y384974D01*
X1563064Y383516D01*
X1558698Y380599D01*
X1556733Y378558D01*
X1555423Y375640D01*
X1554986Y373016D01*
X1564156D01*
G01X1573141Y372433D02*
X1581001Y390516D01*
G01X1590204D02*
Y373016D01*
X1598938D01*
G01X1614691D02*
Y390516D01*
X1606612Y377974D01*
X1617530D01*
G01X1537704Y494466D02*
Y476966D01*
X1546438D01*
G01X1555423Y491549D02*
X1556733Y493299D01*
X1558261Y494174D01*
X1560008Y494466D01*
X1562191Y493883D01*
X1563719Y492424D01*
X1564156Y490675D01*
X1563938Y488924D01*
X1563064Y487466D01*
X1558698Y484549D01*
X1556733Y482508D01*
X1555423Y479590D01*
X1554986Y476966D01*
X1564156D01*
G01X1573141Y476383D02*
X1581001Y494466D01*
G01X1590204D02*
Y476966D01*
X1598938D01*
G01X1614691D02*
Y494466D01*
X1606612Y481924D01*
X1617530D01*
G01X1537704Y459816D02*
Y442316D01*
X1546438D01*
G01X1555423Y456899D02*
X1556733Y458649D01*
X1558261Y459524D01*
X1560008Y459816D01*
X1562191Y459233D01*
X1563719Y457774D01*
X1564156Y456025D01*
X1563938Y454274D01*
X1563064Y452816D01*
X1558698Y449899D01*
X1556733Y447858D01*
X1555423Y444940D01*
X1554986Y442316D01*
X1564156D01*
G01X1573141Y441733D02*
X1581001Y459816D01*
G01X1590204D02*
Y442316D01*
X1598938D01*
G01X1614691D02*
Y459816D01*
X1606612Y447274D01*
X1617530D01*
G01X1773621Y488632D02*
Y476966D01*
G01Y493299D02*
X1773184Y493591D01*
Y494174D01*
X1773621Y494466D01*
X1774058Y494174D01*
Y493591D01*
X1773621Y493299D01*
G01X1787846Y479007D02*
X1788938Y477841D01*
X1790466Y476966D01*
X1791776D01*
X1793086Y477549D01*
X1793959Y478424D01*
X1794396Y479590D01*
X1794178Y481341D01*
X1793304Y482216D01*
X1789374Y483966D01*
X1788501Y486008D01*
X1788938Y487466D01*
X1789811Y488341D01*
X1791121Y488632D01*
X1792431Y488341D01*
X1793741Y487466D01*
G01X1821099Y476966D02*
Y494466D01*
X1831143Y476966D01*
Y494466D01*
G01X1843621Y476966D02*
X1841874Y477258D01*
X1840346Y478424D01*
X1839036Y480174D01*
X1838162Y482216D01*
X1837726Y484549D01*
Y486883D01*
X1838162Y489216D01*
X1839036Y491258D01*
X1840346Y493007D01*
X1841874Y494174D01*
X1843621Y494466D01*
X1845367Y494174D01*
X1846896Y493007D01*
X1848206Y491258D01*
X1849080Y489216D01*
X1849516Y486883D01*
Y484549D01*
X1849080Y482216D01*
X1848206Y480174D01*
X1846896Y478424D01*
X1845367Y477258D01*
X1843621Y476966D01*
G01X1861121Y494466D02*
Y476966D01*
G01X1856099Y494466D02*
X1866143D01*
G01X1892409Y488632D02*
Y480466D01*
X1893283Y478424D01*
X1894593Y477258D01*
X1896121Y476966D01*
X1897649Y477258D01*
X1898959Y478424D01*
X1899833Y480466D01*
G01Y476966D02*
Y488632D01*
G01X1910346Y479007D02*
X1911438Y477841D01*
X1912966Y476966D01*
X1914276D01*
X1915586Y477549D01*
X1916459Y478424D01*
X1916896Y479590D01*
X1916678Y481341D01*
X1915804Y482216D01*
X1911874Y483966D01*
X1911001Y486008D01*
X1911438Y487466D01*
X1912311Y488341D01*
X1913621Y488632D01*
X1914931Y488341D01*
X1916241Y487466D01*
G01X1927846Y484841D02*
X1934833D01*
X1934178Y486883D01*
X1933086Y488049D01*
X1931558Y488632D01*
X1930029Y488341D01*
X1928719Y487466D01*
X1927846Y485424D01*
X1927409Y483674D01*
Y481924D01*
X1927846Y480174D01*
X1928938Y478424D01*
X1930248Y477258D01*
X1931776Y476966D01*
X1933304Y477549D01*
X1934833Y479299D01*
G01X1952551Y494466D02*
Y476966D01*
G01Y479590D02*
X1951678Y478132D01*
X1950367Y477258D01*
X1948839Y476966D01*
X1947093Y477549D01*
X1945783Y479007D01*
X1944909Y480757D01*
X1944691Y482799D01*
X1944909Y484841D01*
X1945783Y486591D01*
X1947093Y488049D01*
X1948839Y488632D01*
X1950367Y488341D01*
X1951459Y487757D01*
X1952551Y486591D01*
G01X1698818Y511033D02*
X1708424Y523866D01*
G01X1703621Y526199D02*
Y508699D01*
G01X1708424Y511033D02*
X1698818Y523866D01*
G01X1697071Y517449D02*
X1710171D01*
G01X1735783D02*
X1741459D01*
G01X1768818Y511616D02*
Y529116D01*
X1773184D01*
X1774931Y528241D01*
X1776241Y527074D01*
X1777333Y525325D01*
X1778206Y523282D01*
X1778424Y520366D01*
X1778206Y517449D01*
X1777333Y515407D01*
X1776241Y513657D01*
X1774931Y512491D01*
X1773184Y511616D01*
X1768818D01*
G01X1787846Y519491D02*
X1794833D01*
X1794178Y521533D01*
X1793086Y522699D01*
X1791558Y523282D01*
X1790029Y522991D01*
X1788719Y522116D01*
X1787846Y520074D01*
X1787409Y518324D01*
Y516574D01*
X1787846Y514824D01*
X1788938Y513074D01*
X1790248Y511908D01*
X1791776Y511616D01*
X1793304Y512199D01*
X1794833Y513949D01*
G01X1804909Y511616D02*
Y523282D01*
G01Y520366D02*
X1805783Y521824D01*
X1807093Y522991D01*
X1808839Y523282D01*
X1810367Y522991D01*
X1811678Y521824D01*
X1812333Y519783D01*
Y511616D01*
G01X1826121D02*
X1824811Y511908D01*
X1823501Y513074D01*
X1822627Y515116D01*
X1822191Y517449D01*
X1822627Y519783D01*
X1823501Y521824D01*
X1824811Y522991D01*
X1826121Y523282D01*
X1827431Y522991D01*
X1828741Y521824D01*
X1829614Y519783D01*
X1829833Y517449D01*
X1829614Y515116D01*
X1828741Y513074D01*
X1827431Y511908D01*
X1826121Y511616D01*
G01X1843621Y529116D02*
Y511616D01*
G01X1840564Y523282D02*
X1846678D01*
G01X1857846Y519491D02*
X1864833D01*
X1864178Y521533D01*
X1863086Y522699D01*
X1861558Y523282D01*
X1860029Y522991D01*
X1858719Y522116D01*
X1857846Y520074D01*
X1857409Y518324D01*
Y516574D01*
X1857846Y514824D01*
X1858938Y513074D01*
X1860248Y511908D01*
X1861776Y511616D01*
X1863304Y512199D01*
X1864833Y513949D01*
G01X1875346Y513657D02*
X1876438Y512491D01*
X1877966Y511616D01*
X1879276D01*
X1880586Y512199D01*
X1881459Y513074D01*
X1881896Y514240D01*
X1881678Y515991D01*
X1880804Y516866D01*
X1876874Y518616D01*
X1876001Y520658D01*
X1876438Y522116D01*
X1877311Y522991D01*
X1878621Y523282D01*
X1879931Y522991D01*
X1881241Y522116D01*
G01X1913621Y529116D02*
Y511616D01*
G01X1910564Y523282D02*
X1916678D01*
G01X1927409Y511616D02*
Y529116D01*
G01Y520658D02*
X1928501Y522116D01*
X1929593Y522991D01*
X1931339Y523282D01*
X1932649Y522991D01*
X1934178Y521824D01*
X1934833Y520074D01*
Y511616D01*
G01X1952551D02*
Y523282D01*
G01Y521241D02*
X1951678Y522407D01*
X1950367Y522991D01*
X1948839Y523282D01*
X1947311Y522699D01*
X1946001Y521533D01*
X1945127Y519783D01*
X1944691Y517449D01*
X1945127Y515116D01*
X1946001Y513366D01*
X1947311Y512199D01*
X1948839Y511616D01*
X1950367Y511908D01*
X1951678Y512782D01*
X1952551Y513949D01*
G01X1966121Y529116D02*
Y511616D01*
G01X1963064Y523282D02*
X1969178D01*
G01X2001121Y529116D02*
Y511616D01*
G01X1998064Y523282D02*
X2004178D01*
G01X2014909Y511616D02*
Y529116D01*
G01Y520658D02*
X2016001Y522116D01*
X2017093Y522991D01*
X2018839Y523282D01*
X2020149Y522991D01*
X2021678Y521824D01*
X2022333Y520074D01*
Y511616D01*
G01X2036121Y523282D02*
Y511616D01*
G01Y527949D02*
X2035684Y528241D01*
Y528824D01*
X2036121Y529116D01*
X2036558Y528824D01*
Y528241D01*
X2036121Y527949D01*
G01X2050346Y513657D02*
X2051438Y512491D01*
X2052966Y511616D01*
X2054276D01*
X2055586Y512199D01*
X2056459Y513074D01*
X2056896Y514240D01*
X2056678Y515991D01*
X2055804Y516866D01*
X2051874Y518616D01*
X2051001Y520658D01*
X2051438Y522116D01*
X2052311Y522991D01*
X2053621Y523282D01*
X2054931Y522991D01*
X2056241Y522116D01*
G01X2086001Y529116D02*
X2091241D01*
G01X2088621D02*
Y511616D01*
G01X2086001D02*
X2091241D01*
G01X2099571D02*
Y523282D01*
G01Y520074D02*
X2100226Y521533D01*
X2101318Y522699D01*
X2102846Y523282D01*
X2104374Y522699D01*
X2105466Y521533D01*
X2106121Y520074D01*
Y511616D01*
G01Y520074D02*
X2106776Y521533D01*
X2107867Y522699D01*
X2109396Y523282D01*
X2110924Y522699D01*
X2112016Y521533D01*
X2112671Y519783D01*
Y511616D01*
G01X2119691Y505783D02*
Y523282D01*
G01Y520658D02*
X2120783Y522116D01*
X2121874Y522991D01*
X2123621Y523282D01*
X2125149Y522991D01*
X2126678Y521533D01*
X2127333Y519491D01*
X2127551Y517449D01*
X2127333Y515407D01*
X2126678Y513366D01*
X2125367Y512199D01*
X2123621Y511616D01*
X2122093Y511908D01*
X2120564Y512782D01*
X2119691Y513949D01*
G01X2137846Y519491D02*
X2144833D01*
X2144178Y521533D01*
X2143086Y522699D01*
X2141558Y523282D01*
X2140029Y522991D01*
X2138719Y522116D01*
X2137846Y520074D01*
X2137409Y518324D01*
Y516574D01*
X2137846Y514824D01*
X2138938Y513074D01*
X2140248Y511908D01*
X2141776Y511616D01*
X2143304Y512199D01*
X2144833Y513949D01*
G01X2162551Y529116D02*
Y511616D01*
G01Y514240D02*
X2161678Y512782D01*
X2160367Y511908D01*
X2158839Y511616D01*
X2157093Y512199D01*
X2155783Y513657D01*
X2154909Y515407D01*
X2154691Y517449D01*
X2154909Y519491D01*
X2155783Y521241D01*
X2157093Y522699D01*
X2158839Y523282D01*
X2160367Y522991D01*
X2161459Y522407D01*
X2162551Y521241D01*
G01X2180051Y511616D02*
Y523282D01*
G01Y521241D02*
X2179178Y522407D01*
X2177867Y522991D01*
X2176339Y523282D01*
X2174811Y522699D01*
X2173501Y521533D01*
X2172627Y519783D01*
X2172191Y517449D01*
X2172627Y515116D01*
X2173501Y513366D01*
X2174811Y512199D01*
X2176339Y511616D01*
X2177867Y511908D01*
X2179178Y512782D01*
X2180051Y513949D01*
G01X2189909Y511616D02*
Y523282D01*
G01Y520366D02*
X2190783Y521824D01*
X2192093Y522991D01*
X2193839Y523282D01*
X2195367Y522991D01*
X2196678Y521824D01*
X2197333Y519783D01*
Y511616D01*
G01X2214614Y521824D02*
X2213086Y522991D01*
X2211776Y523282D01*
X2210029Y522699D01*
X2208719Y521533D01*
X2207846Y519491D01*
X2207627Y517449D01*
X2207846Y515407D01*
X2208719Y513657D01*
X2210029Y512199D01*
X2211776Y511616D01*
X2213304Y512199D01*
X2214614Y513366D01*
G01X2225346Y519491D02*
X2232333D01*
X2231678Y521533D01*
X2230586Y522699D01*
X2229058Y523282D01*
X2227529Y522991D01*
X2226219Y522116D01*
X2225346Y520074D01*
X2224909Y518324D01*
Y516574D01*
X2225346Y514824D01*
X2226438Y513074D01*
X2227748Y511908D01*
X2229276Y511616D01*
X2230804Y512199D01*
X2232333Y513949D01*
G01X20103Y-86244D02*
G03I-4291J0D01*
G01X0Y-87362D02*
G03X15000Y-102362I15000J0D01*
G01X0Y-11811D02*
Y-87362D01*
G01X3937Y-7874D02*
G03X0Y-11811I0J-3937D01*
G01X15748Y-7874D02*
X3937D01*
G01X0Y7874D02*
G03X7874Y0I7874J0D01*
G01X818897D02*
X7874D01*
G01X0Y7874D02*
Y562992D01*
G01X7874Y570866D02*
G03X0Y562992I0J-7874D01*
G01X7874Y570866D02*
X326781D01*
G01X312004Y-102362D02*
X15000D01*
G01X46456Y0D02*
G03Y-7874I0J-3937D01*
G01X15748D02*
G03Y0I0J3937D01*
G01X287400Y-7874D02*
X46456D01*
G01X40452Y499724D02*
G03I-3051J0D01*
G01X41535Y535157D02*
G03I-4134J0D01*
G01X44685Y517441D02*
G03I-7284J0D01*
G01X121082Y39055D02*
G03I-5019J0D01*
G01X120807Y14567D02*
G03I-4744J0D01*
G01X319878Y-102362D02*
G03X312004I-3937J0D01*
G01X811771D02*
X319878D01*
G01X326770Y0D02*
G03Y-7874I0J-3937D01*
G01X287400D02*
G03Y0I0J3937D01*
G01X302165Y531496D02*
G03I-6890J0D01*
G01X597707Y-7874D02*
X326770D01*
G01X379921Y156220D02*
G03I-5906J0D01*
G01X342529Y530315D02*
G03X334655I-3937J0D01*
G01X342529Y520720D02*
G03X352474Y509057I11811J0D01*
G01X334655Y520720D02*
G03X351230Y501282I19685J0D01*
G01X384484Y503937D02*
X352475Y509057D01*
G01X383858Y496063D02*
X351231Y501282D01*
G01X442287Y503937D02*
X384484D01*
G01X442913Y496063D02*
X383858D01*
G01X342529Y530315D02*
Y520720D01*
G01X334655Y562992D02*
Y520720D01*
G01X346466Y570866D02*
G03X342529Y566929I0J-3937D01*
G01X334655Y555512D02*
G03X342529I3937J0D01*
G01X346466Y570866D02*
X480325D01*
G01X334655Y562992D02*
G03X326781Y570866I-7874J0D01*
G01X342529Y566929D02*
Y555512D01*
G01X415943Y539991D02*
G03I-4291J0D01*
G01X474316Y509060D02*
X442287Y503937D01*
G01X475560Y501285D02*
X442913Y496063D01*
G01X492136Y530315D02*
G03X484262I-3937J0D01*
G01X474316Y509060D02*
G03X484262Y520723I-1865J11663D01*
G01X475560Y501285D02*
G03X492136Y520723I-3109J19438D01*
G01X484262Y530315D02*
Y520723D01*
G01X492136Y562992D02*
Y520723D01*
G01X484262Y566929D02*
G03X480325Y570866I-3937J0D01*
G01X484262Y555512D02*
G03X492136I3937J0D01*
G01X500010Y570866D02*
G03X492136Y562992I0J-7874D01*
G01X500010Y570866D02*
X818897D01*
G01X484262Y566929D02*
Y555512D01*
G01X537401Y371299D02*
G03I-5905J0D01*
G01X538386Y531496D02*
G03I-6890J0D01*
G01X628416Y0D02*
G03Y-7874I0J-3937D01*
G01X597707D02*
G03Y0I0J3937D01*
G01X780315Y-7874D02*
X628416D01*
G01X602362Y116141D02*
G03I-5906J0D01*
G01X817003Y-86834D02*
G03I-4292J0D01*
G01X811771Y-102362D02*
G03X826771Y-87362I0J15000D01*
G01X811023Y0D02*
G03Y-7874I0J-3937D01*
G01X780315D02*
G03Y0I0J3937D01*
G01X822834Y-7874D02*
X811023D01*
G01X818897Y0D02*
G03X826771Y7874I0J7874D01*
G01X818897Y0D02*
X807086D01*
G01X787401Y198819D02*
G03I-5905J0D01*
G01X792421Y499724D02*
G03I-3051J0D01*
G01X793504Y535157D02*
G03I-4134J0D01*
G01X796653Y517441D02*
G03I-7283J0D01*
G01X826771Y562992D02*
G03X818897Y570866I-7874J0D01*
G01X826771Y-11811D02*
Y-87362D01*
G01Y-11811D02*
G03X822834Y-7874I-3937J0D01*
G01X826771Y562992D02*
Y7874D01*
M02*
